FILE_TYPE = MACRO_DRAWING;
SET COLOR_WIRE YELLOW;
SET COLOR_PROP MONO;
SET COLOR_DOT WHITE;
SET COLOR_ARC YELLOW;
SET COLOR_BODY GREEN;
SET COLOR_NOTE MONO;
SET PROP_DISPLAY VALUE;
SET PAGE_NUMBER P224;
FORCEADD PVDDQ_GHJ..1
(4000 2050);
FORCEPROP 3 LASTPIN (4000 2000) SIG_NAME PVDDQ_GHJ\g
J 0
(4010 2010);
DISPLAY 0.659574 (4010 2010);
PAINT MONO (4010 2010);
DISPLAY INVISIBLE (4010 2010);
FORCEPROP 1 LAST VOLTAGE 1.2V
J 0
(3955 2007);
DISPLAY 0.340426 (3955 2007);
PAINT SKYBLUE (3955 2007);
DISPLAY INVISIBLE (3955 2007);
FORCEPROP 1 LAST BODY_TYPE PLUMBING
J 0
(3955 2007);
DISPLAY 0.340426 (3955 2007);
PAINT GREEN (3955 2007);
DISPLAY INVISIBLE (3955 2007);
FORCEPROP 1 LAST HDL_POWER PVDDQ_GHJ
J 1
(4000 2100);
DISPLAY 0.872340 (4000 2100);
PAINT GREEN (4000 2100);
DISPLAY INVISIBLE (4000 2100);
FORCEPROP 1 LAST PATH I1
J 0
(4050 2075);
DISPLAY 0.872340 (4050 2075);
PAINT AQUA (4050 2075);
DISPLAY INVISIBLE (4050 2075);
FORCEPROP 2 LAST CDS_LIB mstr_symbols
J 0
(4000 2050);
PAINT ORANGE (4000 2050);
DISPLAY INVISIBLE (4000 2050);
FORCEADD IR354XX..1
(1475 2250);
FORCEPROP 1 LAST PART_NUMBER H73688-001
J 0
(1075 1550);
DISPLAY 0.617021 (1075 1550);
PAINT BLUE (1075 1550);
FORCEPROP 2 LASTPIN (975 1900) $PN 32
J 2
(965 1910);
DISPLAY 0.617021 (965 1910);
PAINT ORANGE (965 1910);
FORCEPROP 2 LASTPIN (975 1950) $PN 33
J 2
(965 1960);
DISPLAY 0.617021 (965 1960);
PAINT ORANGE (965 1960);
FORCEPROP 2 LASTPIN (1975 1750) $PN 7
J 0
(1985 1760);
DISPLAY 0.617021 (1985 1760);
PAINT ORANGE (1985 1760);
FORCEPROP 2 LASTPIN (1975 1700) $PN 5
J 0
(1985 1710);
DISPLAY 0.617021 (1985 1710);
PAINT ORANGE (1985 1710);
FORCEPROP 2 LASTPIN (1975 1800) $PN 40
J 0
(1985 1810);
DISPLAY 0.617021 (1985 1810);
PAINT ORANGE (1985 1810);
FORCEPROP 2 LASTPIN (1975 1850) $PN 2
J 0
(1985 1860);
DISPLAY 0.617021 (1985 1860);
PAINT ORANGE (1985 1860);
FORCEPROP 2 LASTPIN (975 2250) $PN 6
J 2
(965 2260);
DISPLAY 0.617021 (965 2260);
PAINT ORANGE (965 2260);
FORCEPROP 2 LASTPIN (975 2150) $PN 34
J 2
(965 2160);
DISPLAY 0.617021 (965 2160);
PAINT ORANGE (965 2160);
FORCEPROP 2 LASTPIN (975 2050) $PN 39
J 2
(965 2060);
DISPLAY 0.617021 (965 2060);
PAINT ORANGE (965 2060);
FORCEPROP 2 LASTPIN (975 2500) $PN 35
J 2
(965 2510);
DISPLAY 0.617021 (965 2510);
PAINT ORANGE (965 2510);
FORCEPROP 2 LASTPIN (975 2300) $PN 41
J 2
(965 2310);
DISPLAY 0.617021 (965 2310);
PAINT ORANGE (965 2310);
FORCEPROP 2 LASTPIN (975 2400) $PN 1
J 2
(965 2410);
DISPLAY 0.617021 (965 2410);
PAINT ORANGE (965 2410);
FORCEPROP 2 LASTPIN (975 2750) $PN 30
J 2
(965 2760);
DISPLAY 0.617021 (965 2760);
PAINT ORANGE (965 2760);
FORCEPROP 2 LASTPIN (975 2600) $PN 4
J 2
(965 2610);
DISPLAY 0.617021 (965 2610);
PAINT ORANGE (965 2610);
FORCEPROP 2 LASTPIN (975 2800) $PN 3
J 2
(965 2810);
DISPLAY 0.617021 (965 2810);
PAINT ORANGE (965 2810);
FORCEPROP 1 LAST MATERIAL IC
J 0
(1025 3000);
DISPLAY 0.617021 (1025 3000);
PAINT SKYBLUE (1025 3000);
FORCEPROP 1 LAST VALUE IR35411
J 1
(1475 2875);
DISPLAY 0.617021 (1475 2875);
PAINT SKYBLUE (1475 2875);
FORCEPROP 2 LASTPIN (1975 2300) $PN 36
J 0
(1985 2310);
DISPLAY 0.617021 (1985 2310);
PAINT ORANGE (1985 2310);
FORCEPROP 2 LASTPIN (1975 2550) $PN 31
J 0
(1985 2560);
DISPLAY 0.617021 (1985 2560);
PAINT ORANGE (1985 2560);
FORCEPROP 2 LASTPIN (1975 2600) $PN 37
J 0
(1985 2610);
DISPLAY 0.617021 (1985 2610);
PAINT ORANGE (1985 2610);
FORCEPROP 2 LASTPIN (1975 2800) $PN 38
J 0
(1985 2810);
DISPLAY 0.617021 (1985 2810);
PAINT ORANGE (1985 2810);
FORCEPROP 1 LAST LOCATION EU1G1
J 0
(1025 3050);
DISPLAY 0.617021 (1025 3050);
PAINT AQUA (1025 3050);
FORCEPROP 2 LAST NO_XNET_CONNECTION 1
J 0
(1025 3100);
PAINT MONO (1025 3100);
FORCEPROP 2 LASTPIN (975 2700) $PN 25
J 2
(965 2710);
DISPLAY 0.617021 (965 2710);
PAINT ORANGE (965 2710);
FORCEPROP 2 LASTPIN (1975 1950) $PN 10
J 0
(1985 1960);
DISPLAY 0.617021 (1985 1960);
PAINT ORANGE (1985 1960);
FORCEPROP 1 LAST PATH I110
J 0
(1475 3000);
PAINT GREEN (1475 3000);
DISPLAY INVISIBLE (1475 3000);
FORCEPROP 2 LAST CDS_LIB mstr_discrete
J 0
(1475 2250);
PAINT ORANGE (1475 2250);
DISPLAY INVISIBLE (1475 2250);
FORCEPROP 2 LAST CDS_LOCATION EU1G1
J 0
(1025 3050);
PAINT GREEN (1025 3050);
DISPLAY INVISIBLE (1025 3050);
FORCEPROP 2 LAST SEC 1
J 0
(1025 3100);
DISPLAY 0.680851 (1025 3100);
PAINT MONO (1025 3100);
DISPLAY INVISIBLE (1025 3100);
FORCEPROP 2 LAST SEC_TYPE SM
J 0
(1025 3100);
DISPLAY 1.021277 (1025 3100);
PAINT ORANGE (1025 3100);
DISPLAY INVISIBLE (1025 3100);
FORCEPROP 1 LAST PACK_TYPE SM
J 0
(1025 3100);
PAINT SKYBLUE (1025 3100);
DISPLAY INVISIBLE (1025 3100);
FORCEADD IR354XX..1
(1500 -125);
FORCEPROP 2 LASTPIN (2000 -425) $PN 10
J 0
(2010 -415);
DISPLAY 0.617021 (2010 -415);
PAINT ORANGE (2010 -415);
FORCEPROP 2 LASTPIN (1000 -325) $PN 39
J 2
(990 -315);
DISPLAY 0.617021 (990 -315);
PAINT ORANGE (990 -315);
FORCEPROP 2 LASTPIN (1000 -475) $PN 32
J 2
(990 -465);
DISPLAY 0.617021 (990 -465);
PAINT ORANGE (990 -465);
FORCEPROP 2 LASTPIN (1000 -425) $PN 33
J 2
(990 -415);
DISPLAY 0.617021 (990 -415);
PAINT ORANGE (990 -415);
FORCEPROP 2 LASTPIN (1000 -225) $PN 34
J 2
(990 -215);
DISPLAY 0.617021 (990 -215);
PAINT ORANGE (990 -215);
FORCEPROP 2 LASTPIN (1000 -75) $PN 41
J 2
(990 -65);
DISPLAY 0.617021 (990 -65);
PAINT ORANGE (990 -65);
FORCEPROP 2 LASTPIN (1000 -125) $PN 6
J 2
(990 -115);
DISPLAY 0.617021 (990 -115);
PAINT ORANGE (990 -115);
FORCEPROP 2 LASTPIN (2000 -625) $PN 7
J 0
(2010 -615);
DISPLAY 0.617021 (2010 -615);
PAINT ORANGE (2010 -615);
FORCEPROP 2 LASTPIN (2000 -675) $PN 5
J 0
(2010 -665);
DISPLAY 0.617021 (2010 -665);
PAINT ORANGE (2010 -665);
FORCEPROP 2 LASTPIN (2000 -525) $PN 2
J 0
(2010 -515);
DISPLAY 0.617021 (2010 -515);
PAINT ORANGE (2010 -515);
FORCEPROP 2 LASTPIN (2000 -575) $PN 40
J 0
(2010 -565);
DISPLAY 0.617021 (2010 -565);
PAINT ORANGE (2010 -565);
FORCEPROP 2 LASTPIN (1000 25) $PN 1
J 2
(990 35);
DISPLAY 0.617021 (990 35);
PAINT ORANGE (990 35);
FORCEPROP 2 LASTPIN (1000 125) $PN 35
J 2
(990 135);
DISPLAY 0.617021 (990 135);
PAINT ORANGE (990 135);
FORCEPROP 2 LASTPIN (1000 225) $PN 4
J 2
(990 235);
DISPLAY 0.617021 (990 235);
PAINT ORANGE (990 235);
FORCEPROP 2 LASTPIN (1000 375) $PN 30
J 2
(990 385);
DISPLAY 0.617021 (990 385);
PAINT ORANGE (990 385);
FORCEPROP 2 LASTPIN (1000 325) $PN 25
J 2
(990 335);
DISPLAY 0.617021 (990 335);
PAINT ORANGE (990 335);
FORCEPROP 2 LASTPIN (1000 425) $PN 3
J 2
(990 435);
DISPLAY 0.617021 (990 435);
PAINT ORANGE (990 435);
FORCEPROP 1 LAST MATERIAL IC
J 0
(1050 625);
DISPLAY 0.617021 (1050 625);
PAINT SKYBLUE (1050 625);
FORCEPROP 1 LAST LOCATION EU1F1
J 0
(1050 675);
DISPLAY 0.617021 (1050 675);
PAINT AQUA (1050 675);
FORCEPROP 1 LAST VALUE IR35411
J 1
(1500 500);
DISPLAY 0.617021 (1500 500);
PAINT SKYBLUE (1500 500);
FORCEPROP 2 LASTPIN (2000 425) $PN 38
J 0
(2010 435);
DISPLAY 0.617021 (2010 435);
PAINT ORANGE (2010 435);
FORCEPROP 2 LASTPIN (2000 175) $PN 31
J 0
(2010 185);
DISPLAY 0.617021 (2010 185);
PAINT ORANGE (2010 185);
FORCEPROP 2 LASTPIN (2000 225) $PN 37
J 0
(2010 235);
DISPLAY 0.617021 (2010 235);
PAINT ORANGE (2010 235);
FORCEPROP 1 LAST PART_NUMBER H73688-001
J 0
(1050 -825);
DISPLAY 0.617021 (1050 -825);
PAINT BLUE (1050 -825);
FORCEPROP 2 LASTPIN (2000 -75) $PN 36
J 0
(2010 -65);
DISPLAY 0.617021 (2010 -65);
PAINT ORANGE (2010 -65);
FORCEPROP 2 LAST CDS_LIB mstr_discrete
J 0
(1500 -125);
PAINT ORANGE (1500 -125);
DISPLAY INVISIBLE (1500 -125);
FORCEPROP 1 LAST PATH I111
J 0
(1500 625);
PAINT GREEN (1500 625);
DISPLAY INVISIBLE (1500 625);
FORCEPROP 2 LAST CDS_LOCATION EU1F1
J 0
(1050 675);
PAINT GREEN (1050 675);
DISPLAY INVISIBLE (1050 675);
FORCEPROP 2 LAST SEC 1
J 0
(1050 725);
DISPLAY 0.680851 (1050 725);
PAINT MONO (1050 725);
DISPLAY INVISIBLE (1050 725);
FORCEPROP 2 LAST SEC_TYPE SM
J 0
(1050 725);
DISPLAY 1.021277 (1050 725);
PAINT ORANGE (1050 725);
DISPLAY INVISIBLE (1050 725);
FORCEPROP 1 LAST PACK_TYPE SM
J 0
(1050 725);
PAINT SKYBLUE (1050 725);
DISPLAY INVISIBLE (1050 725);
FORCEADD RES..2
(4275 2400);
FORCEPROP 1 LAST WATTAGE 1/16W
J 0
(4315 2375);
DISPLAY 0.617021 (4315 2375);
PAINT SKYBLUE (4315 2375);
FORCEPROP 1 LAST PACK_TYPE 0402
J 0
(4315 2225);
DISPLAY 0.617021 (4315 2225);
PAINT SKYBLUE (4315 2225);
FORCEPROP 1 LAST TOLERANCE 1%
J 0
(4320 2425);
DISPLAY 0.617021 (4320 2425);
PAINT SKYBLUE (4320 2425);
FORCEPROP 1 LAST VALUE 68.1K
J 0
(4320 2475);
DISPLAY 0.617021 (4320 2475);
PAINT SKYBLUE (4320 2475);
FORCEPROP 1 LAST PART_NUMBER G21796-187
J 0
(4315 2275);
DISPLAY 0.617021 (4315 2275);
PAINT BLUE (4315 2275);
FORCEPROP 1 LAST LOCATION R1G26
J 0
(4320 2525);
DISPLAY 0.617021 (4320 2525);
PAINT AQUA (4320 2525);
FORCEPROP 1 LAST MATERIAL EMPTY
J 0
(4315 2325);
DISPLAY 0.617021 (4315 2325);
PAINT RED (4315 2325);
FORCEPROP 1 LASTPIN (4275 2300) $PN 2
J 0
(4280 2310);
DISPLAY 0.787234 (4280 2310);
PAINT ORANGE (4280 2310);
DISPLAY INVISIBLE (4280 2310);
FORCEPROP 2 LAST CDS_LIB mstr_discrete
J 0
(4275 2400);
PAINT ORANGE (4275 2400);
DISPLAY INVISIBLE (4275 2400);
FORCEPROP 1 LASTPIN (4275 2500) $PN 1
J 0
(4280 2462);
DISPLAY 0.787234 (4280 2462);
PAINT ORANGE (4280 2462);
DISPLAY INVISIBLE (4280 2462);
FORCEPROP 1 LAST PATH I112
J 0
(4325 2575);
DISPLAY 0.978723 (4325 2575);
PAINT WHITE (4325 2575);
DISPLAY INVISIBLE (4325 2575);
FORCEPROP 2 LAST $SEC 1
J 0
(4325 2625);
PAINT MONO (4325 2625);
DISPLAY INVISIBLE (4325 2625);
FORCEPROP 2 LAST CDS_SEC 1
J 0
(4325 2625);
PAINT MONO (4325 2625);
DISPLAY INVISIBLE (4325 2625);
FORCEADD GND..1
(4275 2100);
FORCEPROP 3 LASTPIN (4275 2150) SIG_NAME GND\g
J 0
(4285 2160);
DISPLAY 0.659574 (4285 2160);
PAINT MONO (4285 2160);
DISPLAY INVISIBLE (4285 2160);
FORCEPROP 2 LAST ROOM PVCCIN_CPU0_PWR_VR
J 0
(3725 2175);
DISPLAY 1.936170 (3725 2175);
PAINT ORANGE (3725 2175);
DISPLAY INVISIBLE (3725 2175);
FORCEPROP 2 LAST BOM_COST PROC_VRD_VCCIN_CPU0
J 0
(3900 2175);
DISPLAY 1.446809 (3900 2175);
PAINT MONO (3900 2175);
DISPLAY INVISIBLE (3900 2175);
FORCEPROP 1 LAST PATH I113
J 0
(4350 2100);
DISPLAY 0.872340 (4350 2100);
PAINT AQUA (4350 2100);
DISPLAY INVISIBLE (4350 2100);
FORCEPROP 1 LAST BODY_TYPE PLUMBING
J 0
(4230 2057);
DISPLAY 0.340426 (4230 2057);
PAINT GREEN (4230 2057);
DISPLAY INVISIBLE (4230 2057);
FORCEPROP 1 LAST SIZE 1B
J 0
(4350 2050);
DISPLAY 1.723404 (4350 2050);
PAINT GREEN (4350 2050);
DISPLAY INVISIBLE (4350 2050);
FORCEPROP 2 LAST CDS_LIB mstr_symbols
J 0
(4275 2100);
PAINT ORANGE (4275 2100);
DISPLAY INVISIBLE (4275 2100);
FORCEPROP 1 LAST VOLTAGE 0
J 0
(4275 2100);
PAINT SKYBLUE (4275 2100);
DISPLAY INVISIBLE (4275 2100);
FORCEPROP 1 LAST HDL_POWER GND
J 0
(4275 2250);
DISPLAY 1.723404 (4275 2250);
PAINT GREEN (4275 2250);
DISPLAY INVISIBLE (4275 2250);
FORCEADD RES..2
(4300 25);
FORCEPROP 1 LAST PACK_TYPE 0402
J 0
(4340 -150);
DISPLAY 0.617021 (4340 -150);
PAINT SKYBLUE (4340 -150);
FORCEPROP 1 LAST MATERIAL EMPTY
J 0
(4340 -50);
DISPLAY 0.617021 (4340 -50);
PAINT RED (4340 -50);
FORCEPROP 1 LAST PART_NUMBER G21796-187
J 0
(4340 -100);
DISPLAY 0.617021 (4340 -100);
PAINT BLUE (4340 -100);
FORCEPROP 1 LAST WATTAGE 1/16W
J 0
(4340 0);
DISPLAY 0.617021 (4340 0);
PAINT SKYBLUE (4340 0);
FORCEPROP 1 LAST TOLERANCE 1%
J 0
(4345 50);
DISPLAY 0.617021 (4345 50);
PAINT SKYBLUE (4345 50);
FORCEPROP 1 LAST VALUE 68.1K
J 0
(4345 100);
DISPLAY 0.617021 (4345 100);
PAINT SKYBLUE (4345 100);
FORCEPROP 1 LAST LOCATION R1G25
J 0
(4345 150);
DISPLAY 0.617021 (4345 150);
PAINT AQUA (4345 150);
FORCEPROP 1 LASTPIN (4300 -75) $PN 2
J 0
(4305 -65);
DISPLAY 0.787234 (4305 -65);
PAINT ORANGE (4305 -65);
DISPLAY INVISIBLE (4305 -65);
FORCEPROP 1 LASTPIN (4300 125) $PN 1
J 0
(4305 87);
DISPLAY 0.787234 (4305 87);
PAINT ORANGE (4305 87);
DISPLAY INVISIBLE (4305 87);
FORCEPROP 2 LAST CDS_LIB mstr_discrete
J 0
(4300 25);
PAINT ORANGE (4300 25);
DISPLAY INVISIBLE (4300 25);
FORCEPROP 1 LAST PATH I114
J 0
(4350 200);
DISPLAY 0.978723 (4350 200);
PAINT WHITE (4350 200);
DISPLAY INVISIBLE (4350 200);
FORCEPROP 2 LAST $SEC 1
J 0
(4350 250);
PAINT MONO (4350 250);
DISPLAY INVISIBLE (4350 250);
FORCEPROP 2 LAST CDS_SEC 1
J 0
(4350 250);
PAINT MONO (4350 250);
DISPLAY INVISIBLE (4350 250);
FORCEADD GND..1
(4300 -275);
FORCEPROP 3 LASTPIN (4300 -225) SIG_NAME GND\g
J 0
(4310 -215);
DISPLAY 0.659574 (4310 -215);
PAINT MONO (4310 -215);
DISPLAY INVISIBLE (4310 -215);
FORCEPROP 2 LAST ROOM PVCCIN_CPU0_PWR_VR
J 0
(3750 -200);
DISPLAY 1.936170 (3750 -200);
PAINT ORANGE (3750 -200);
DISPLAY INVISIBLE (3750 -200);
FORCEPROP 2 LAST BOM_COST PROC_VRD_VCCIN_CPU0
J 0
(3925 -200);
DISPLAY 1.446809 (3925 -200);
PAINT MONO (3925 -200);
DISPLAY INVISIBLE (3925 -200);
FORCEPROP 1 LAST BODY_TYPE PLUMBING
J 0
(4255 -318);
DISPLAY 0.340426 (4255 -318);
PAINT GREEN (4255 -318);
DISPLAY INVISIBLE (4255 -318);
FORCEPROP 2 LAST CDS_LIB mstr_symbols
J 0
(4300 -275);
PAINT ORANGE (4300 -275);
DISPLAY INVISIBLE (4300 -275);
FORCEPROP 1 LAST VOLTAGE 0
J 0
(4300 -275);
PAINT SKYBLUE (4300 -275);
DISPLAY INVISIBLE (4300 -275);
FORCEPROP 1 LAST HDL_POWER GND
J 0
(4300 -125);
DISPLAY 1.723404 (4300 -125);
PAINT GREEN (4300 -125);
DISPLAY INVISIBLE (4300 -125);
FORCEPROP 1 LAST PATH I115
J 0
(4375 -275);
DISPLAY 0.872340 (4375 -275);
PAINT AQUA (4375 -275);
DISPLAY INVISIBLE (4375 -275);
FORCEPROP 1 LAST SIZE 1B
J 0
(4375 -325);
DISPLAY 1.723404 (4375 -325);
PAINT GREEN (4375 -325);
DISPLAY INVISIBLE (4375 -325);
FORCEADD CAP_A..1
(700 1725);
FORCEPROP 1 LAST LOCATION CT30
J 0
(550 1675);
DISPLAY 0.617021 (550 1675);
PAINT AQUA (550 1675);
FORCEPROP 0 LAST STATUS NOPOP
J 0
(475 1600);
DISPLAY 1.021277 (475 1600);
PAINT ORANGE (475 1600);
FORCEPROP 1 LAST VOLTAGE 16V
J 0
(750 1725);
DISPLAY 0.617021 (750 1725);
PAINT SKYBLUE (750 1725);
FORCEPROP 1 LAST VALUE 0.1UF
J 0
(750 1775);
DISPLAY 0.617021 (750 1775);
PAINT SKYBLUE (750 1775);
FORCEPROP 1 LAST PACK_TYPE 0402V
J 0
(750 1525);
DISPLAY 0.617021 (750 1525);
PAINT SKYBLUE (750 1525);
FORCEPROP 1 LAST PART_NUMBER A36096-030
J 0
(750 1575);
DISPLAY 0.617021 (750 1575);
PAINT BLUE (750 1575);
FORCEPROP 1 LAST MATERIAL X7R
J 0
(750 1625);
DISPLAY 0.617021 (750 1625);
PAINT SKYBLUE (750 1625);
FORCEPROP 1 LAST TOLERANCE 10%
J 0
(750 1675);
DISPLAY 0.617021 (750 1675);
PAINT SKYBLUE (750 1675);
FORCEPROP 1 LASTPIN (700 1625) $PN 2
J 0
(710 1605);
DISPLAY 0.787234 (710 1605);
PAINT ORANGE (710 1605);
DISPLAY INVISIBLE (710 1605);
FORCEPROP 1 LASTPIN (700 1825) $PN 1
J 0
(710 1805);
DISPLAY 0.787234 (710 1805);
PAINT ORANGE (710 1805);
DISPLAY INVISIBLE (710 1805);
FORCEPROP 2 LAST ROOM PVCCIN_CPU0_PWR_VR
J 0
(750 1875);
DISPLAY 1.361702 (750 1875);
PAINT ORANGE (750 1875);
DISPLAY INVISIBLE (750 1875);
FORCEPROP 1 LAST PATH I117
J 0
(750 1875);
DISPLAY 0.978723 (750 1875);
PAINT WHITE (750 1875);
DISPLAY INVISIBLE (750 1875);
FORCEPROP 2 LAST CDS_LIB dev_discrete
J 0
(700 1725);
PAINT MONO (700 1725);
DISPLAY INVISIBLE (700 1725);
FORCEADD GND..1
(700 1475);
FORCEPROP 3 LASTPIN (700 1525) SIG_NAME GND\g
J 0
(710 1535);
DISPLAY 0.659574 (710 1535);
PAINT MONO (710 1535);
DISPLAY INVISIBLE (710 1535);
FORCEPROP 1 LAST HDL_POWER GND
J 0
(700 1625);
DISPLAY 1.723404 (700 1625);
PAINT GREEN (700 1625);
DISPLAY INVISIBLE (700 1625);
FORCEPROP 1 LAST VOLTAGE 0
J 0
(700 1475);
PAINT SKYBLUE (700 1475);
DISPLAY INVISIBLE (700 1475);
FORCEPROP 1 LAST SIZE 1B
J 0
(775 1425);
DISPLAY 1.723404 (775 1425);
PAINT GREEN (775 1425);
DISPLAY INVISIBLE (775 1425);
FORCEPROP 2 LAST BOM_COST PROC_VRD_VCCIN_CPU0
J 0
(325 1550);
DISPLAY 1.446809 (325 1550);
PAINT MONO (325 1550);
DISPLAY INVISIBLE (325 1550);
FORCEPROP 2 LAST ROOM PVCCIN_CPU0_PWR_VR
J 0
(150 1550);
DISPLAY 1.936170 (150 1550);
PAINT ORANGE (150 1550);
DISPLAY INVISIBLE (150 1550);
FORCEPROP 1 LAST BODY_TYPE PLUMBING
J 0
(655 1432);
DISPLAY 0.340426 (655 1432);
PAINT GREEN (655 1432);
DISPLAY INVISIBLE (655 1432);
FORCEPROP 1 LAST PATH I118
J 0
(775 1475);
DISPLAY 0.872340 (775 1475);
PAINT AQUA (775 1475);
DISPLAY INVISIBLE (775 1475);
FORCEPROP 2 LAST CDS_LIB mstr_symbols
J 0
(700 1475);
PAINT MONO (700 1475);
DISPLAY INVISIBLE (700 1475);
FORCEADD 3D01R5F-GP..1
R 4
(2700 1500);
FORCEPROP 0 LAST STATUS NOPOP
J 0
(2400 1500);
DISPLAY 1.021277 (2400 1500);
PAINT ORANGE (2400 1500);
FORCEPROP 1 LAST LOCATION RT20
J 0
(2575 1470);
DISPLAY 0.617021 (2575 1470);
PAINT GREEN (2575 1470);
FORCEPROP 1 LAST VALUE 3D01R5F-GP
J 0
(2400 1425);
DISPLAY 0.617021 (2400 1425);
PAINT GREEN (2400 1425);
FORCEPROP 1 LAST CDS_LMAN_SYM_OUTLINE -50,75,50,-75
R 2
J 0
(2700 1500);
DISPLAY 0.468085 (2700 1500);
PAINT GREEN (2700 1500);
DISPLAY INVISIBLE (2700 1500);
FORCEPROP 1 LAST PATH I119
R 2
J 0
(2700 1500);
DISPLAY 0.617021 (2700 1500);
PAINT GREEN (2700 1500);
DISPLAY INVISIBLE (2700 1500);
FORCEPROP 2 LAST CDS_LIB w_hdl
J 0
(2700 1500);
PAINT MONO (2700 1500);
DISPLAY INVISIBLE (2700 1500);
FORCEPROP 1 LAST PART_NUMBER 64.3R015.16L
R 2
J 0
(2700 1500);
DISPLAY 0.617021 (2700 1500);
PAINT GREEN (2700 1500);
DISPLAY INVISIBLE (2700 1500);
FORCEPROP 1 LAST PACK_TYPE SMD-RG5
R 2
J 0
(2700 1500);
DISPLAY 0.617021 (2700 1500);
PAINT GREEN (2700 1500);
DISPLAY INVISIBLE (2700 1500);
FORCEPROP 2 LASTPIN (2700 1625) SIG_NAME UN$224$3D01R5F-GP$I119$2
J 0
(2710 1635);
DISPLAY 0.659574 (2710 1635);
PAINT MONO (2710 1635);
DISPLAY INVISIBLE (2710 1635);
FORCEADD GND..1
(2700 1275);
FORCEPROP 3 LASTPIN (2700 1325) SIG_NAME GND\g
J 0
(2710 1335);
DISPLAY 0.659574 (2710 1335);
PAINT MONO (2710 1335);
DISPLAY INVISIBLE (2710 1335);
FORCEPROP 1 LAST HDL_POWER GND
J 0
(2700 1425);
DISPLAY 1.723404 (2700 1425);
PAINT GREEN (2700 1425);
DISPLAY INVISIBLE (2700 1425);
FORCEPROP 1 LAST SIZE 1B
J 0
(2775 1225);
DISPLAY 1.723404 (2775 1225);
PAINT GREEN (2775 1225);
DISPLAY INVISIBLE (2775 1225);
FORCEPROP 1 LAST VOLTAGE 0
J 0
(2700 1275);
PAINT SKYBLUE (2700 1275);
DISPLAY INVISIBLE (2700 1275);
FORCEPROP 1 LAST BODY_TYPE PLUMBING
J 0
(2655 1232);
DISPLAY 0.340426 (2655 1232);
PAINT GREEN (2655 1232);
DISPLAY INVISIBLE (2655 1232);
FORCEPROP 2 LAST BOM_COST PROC_VRD_VCCIN_CPU0
J 0
(2325 1350);
DISPLAY 1.446809 (2325 1350);
PAINT MONO (2325 1350);
DISPLAY INVISIBLE (2325 1350);
FORCEPROP 2 LAST ROOM PVCCIN_CPU0_PWR_VR
J 0
(2150 1350);
DISPLAY 1.936170 (2150 1350);
PAINT ORANGE (2150 1350);
DISPLAY INVISIBLE (2150 1350);
FORCEPROP 1 LAST PATH I120
J 0
(2775 1275);
DISPLAY 0.872340 (2775 1275);
PAINT AQUA (2775 1275);
DISPLAY INVISIBLE (2775 1275);
FORCEPROP 2 LAST CDS_LIB mstr_symbols
J 0
(2700 1275);
PAINT MONO (2700 1275);
DISPLAY INVISIBLE (2700 1275);
FORCEADD SC2K2P50V3KX-GP..1
(2700 1800);
FORCEPROP 1 LAST VALUE SC2K2P50V3KX-GP
J 0
(2725 1750);
DISPLAY 0.617021 (2725 1750);
PAINT GREEN (2725 1750);
FORCEPROP 0 LAST STATUS NOPOP
J 0
(2425 1800);
DISPLAY 1.021277 (2425 1800);
PAINT ORANGE (2425 1800);
FORCEPROP 1 LAST LOCATION CT29
J 0
(2725 1830);
DISPLAY 0.617021 (2725 1830);
PAINT GREEN (2725 1830);
FORCEPROP 1 LAST PACK_TYPE SMD-BCG6
J 0
(2700 1800);
DISPLAY 0.617021 (2700 1800);
PAINT GREEN (2700 1800);
DISPLAY INVISIBLE (2700 1800);
FORCEPROP 1 LAST PART_NUMBER 78.22224.2BL
J 0
(2700 1800);
DISPLAY 0.617021 (2700 1800);
PAINT GREEN (2700 1800);
DISPLAY INVISIBLE (2700 1800);
FORCEPROP 1 LAST PATH I121
J 0
(2700 1800);
DISPLAY 0.617021 (2700 1800);
PAINT GREEN (2700 1800);
DISPLAY INVISIBLE (2700 1800);
FORCEPROP 2 LAST CDS_LIB w_hdl
J 0
(2700 1800);
PAINT MONO (2700 1800);
DISPLAY INVISIBLE (2700 1800);
FORCEPROP 1 LAST CDS_LMAN_SYM_OUTLINE -50,25,50,-25
J 0
(2700 1800);
DISPLAY 0.468085 (2700 1800);
PAINT GREEN (2700 1800);
DISPLAY INVISIBLE (2700 1800);
FORCEADD CAP..1
(2600 2225);
FORCEPROP 1 LAST LOCATION CT28
J 0
(2450 2225);
DISPLAY 0.617021 (2450 2225);
PAINT AQUA (2450 2225);
FORCEPROP 1 LAST VOLTAGE 50V
J 0
(2650 2225);
DISPLAY 0.617021 (2650 2225);
PAINT SKYBLUE (2650 2225);
FORCEPROP 1 LAST VALUE 1000PF
J 0
(2650 2275);
DISPLAY 0.617021 (2650 2275);
PAINT SKYBLUE (2650 2275);
FORCEPROP 1 LAST TOLERANCE 10%
J 0
(2650 2175);
DISPLAY 0.617021 (2650 2175);
PAINT SKYBLUE (2650 2175);
FORCEPROP 1 LAST PART_NUMBER A36096-046
J 0
(2650 2075);
DISPLAY 0.617021 (2650 2075);
PAINT BLUE (2650 2075);
FORCEPROP 0 LAST STATUS NOPOP
J 0
(2350 2300);
DISPLAY 1.021277 (2350 2300);
PAINT ORANGE (2350 2300);
FORCEPROP 1 LAST MATERIAL X7R
J 0
(2650 2125);
DISPLAY 0.617021 (2650 2125);
PAINT SKYBLUE (2650 2125);
FORCEPROP 1 LAST PACK_TYPE 0402LF
J 0
(2650 2025);
DISPLAY 0.617021 (2650 2025);
PAINT SKYBLUE (2650 2025);
FORCEPROP 1 LASTPIN (2600 2325) $PN 1
J 0
(2610 2305);
DISPLAY 0.787234 (2610 2305);
PAINT ORANGE (2610 2305);
DISPLAY INVISIBLE (2610 2305);
FORCEPROP 1 LASTPIN (2600 2125) $PN 2
J 0
(2610 2105);
DISPLAY 0.787234 (2610 2105);
PAINT ORANGE (2610 2105);
DISPLAY INVISIBLE (2610 2105);
FORCEPROP 0 LAST ROOM VDDQ_KLM_PWR_VR
J 0
(2650 2425);
DISPLAY 1.021277 (2650 2425);
PAINT ORANGE (2650 2425);
DISPLAY INVISIBLE (2650 2425);
FORCEPROP 1 LAST PATH I122
J 0
(2650 2375);
DISPLAY 0.978723 (2650 2375);
PAINT WHITE (2650 2375);
DISPLAY INVISIBLE (2650 2375);
FORCEPROP 2 LAST CDS_LIB mstr_discrete
J 0
(2600 2225);
PAINT MONO (2600 2225);
DISPLAY INVISIBLE (2600 2225);
FORCEADD GND..1
(2600 2025);
FORCEPROP 3 LASTPIN (2600 2075) SIG_NAME GND\g
J 0
(2610 2085);
DISPLAY 0.659574 (2610 2085);
PAINT MONO (2610 2085);
DISPLAY INVISIBLE (2610 2085);
FORCEPROP 1 LAST HDL_POWER GND
J 0
(2600 2175);
DISPLAY 1.170213 (2600 2175);
PAINT GREEN (2600 2175);
DISPLAY INVISIBLE (2600 2175);
FORCEPROP 1 LAST SIZE 1B
J 0
(2675 1975);
DISPLAY 1.170213 (2675 1975);
PAINT AQUA (2675 1975);
DISPLAY INVISIBLE (2675 1975);
FORCEPROP 1 LAST BODY_TYPE PLUMBING
J 0
(2555 1982);
DISPLAY 0.340426 (2555 1982);
PAINT GREEN (2555 1982);
DISPLAY INVISIBLE (2555 1982);
FORCEPROP 1 LAST VOLTAGE 0
J 0
(2600 2025);
PAINT SKYBLUE (2600 2025);
DISPLAY INVISIBLE (2600 2025);
FORCEPROP 2 LAST ROOM VDDQ_KLM_PWR_VR
J 0
(2025 2100);
DISPLAY 1.361702 (2025 2100);
PAINT ORANGE (2025 2100);
DISPLAY INVISIBLE (2025 2100);
FORCEPROP 1 LAST PATH I123
J 0
(2675 2025);
DISPLAY 0.872340 (2675 2025);
PAINT AQUA (2675 2025);
DISPLAY INVISIBLE (2675 2025);
FORCEPROP 2 LAST CDS_LIB mstr_symbols
J 0
(2600 2025);
PAINT MONO (2600 2025);
DISPLAY INVISIBLE (2600 2025);
FORCEADD CAP_A..1
(800 -625);
FORCEPROP 0 LAST STATUS NOPOP
J 0
(575 -750);
DISPLAY 1.021277 (575 -750);
PAINT ORANGE (575 -750);
FORCEPROP 1 LAST PACK_TYPE 0402V
J 0
(850 -825);
DISPLAY 0.617021 (850 -825);
PAINT SKYBLUE (850 -825);
FORCEPROP 1 LAST LOCATION CT31
J 0
(650 -625);
DISPLAY 0.617021 (650 -625);
PAINT AQUA (650 -625);
FORCEPROP 1 LAST PART_NUMBER A36096-030
J 0
(850 -775);
DISPLAY 0.617021 (850 -775);
PAINT BLUE (850 -775);
FORCEPROP 1 LAST MATERIAL X7R
J 0
(850 -725);
DISPLAY 0.617021 (850 -725);
PAINT SKYBLUE (850 -725);
FORCEPROP 1 LAST TOLERANCE 10%
J 0
(850 -675);
DISPLAY 0.617021 (850 -675);
PAINT SKYBLUE (850 -675);
FORCEPROP 1 LAST VOLTAGE 16V
J 0
(850 -625);
DISPLAY 0.617021 (850 -625);
PAINT SKYBLUE (850 -625);
FORCEPROP 1 LAST VALUE 0.1UF
J 0
(850 -575);
DISPLAY 0.617021 (850 -575);
PAINT SKYBLUE (850 -575);
FORCEPROP 1 LASTPIN (800 -725) $PN 2
J 0
(810 -745);
DISPLAY 0.787234 (810 -745);
PAINT ORANGE (810 -745);
DISPLAY INVISIBLE (810 -745);
FORCEPROP 1 LASTPIN (800 -525) $PN 1
J 0
(810 -545);
DISPLAY 0.787234 (810 -545);
PAINT ORANGE (810 -545);
DISPLAY INVISIBLE (810 -545);
FORCEPROP 2 LAST ROOM PVCCIN_CPU0_PWR_VR
J 0
(850 -475);
DISPLAY 1.361702 (850 -475);
PAINT ORANGE (850 -475);
DISPLAY INVISIBLE (850 -475);
FORCEPROP 1 LAST PATH I124
J 0
(850 -475);
DISPLAY 0.978723 (850 -475);
PAINT WHITE (850 -475);
DISPLAY INVISIBLE (850 -475);
FORCEPROP 2 LAST CDS_LIB dev_discrete
J 0
(800 -625);
PAINT MONO (800 -625);
DISPLAY INVISIBLE (800 -625);
FORCEADD GND..1
(800 -875);
FORCEPROP 3 LASTPIN (800 -825) SIG_NAME GND\g
J 0
(810 -815);
DISPLAY 0.659574 (810 -815);
PAINT MONO (810 -815);
DISPLAY INVISIBLE (810 -815);
FORCEPROP 2 LAST CDS_LIB mstr_symbols
J 0
(800 -875);
PAINT MONO (800 -875);
DISPLAY INVISIBLE (800 -875);
FORCEPROP 1 LAST PATH I125
J 0
(875 -875);
DISPLAY 0.872340 (875 -875);
PAINT AQUA (875 -875);
DISPLAY INVISIBLE (875 -875);
FORCEPROP 1 LAST HDL_POWER GND
J 0
(800 -725);
DISPLAY 1.723404 (800 -725);
PAINT GREEN (800 -725);
DISPLAY INVISIBLE (800 -725);
FORCEPROP 1 LAST VOLTAGE 0
J 0
(800 -875);
PAINT SKYBLUE (800 -875);
DISPLAY INVISIBLE (800 -875);
FORCEPROP 1 LAST SIZE 1B
J 0
(875 -925);
DISPLAY 1.723404 (875 -925);
PAINT GREEN (875 -925);
DISPLAY INVISIBLE (875 -925);
FORCEPROP 2 LAST BOM_COST PROC_VRD_VCCIN_CPU0
J 0
(425 -800);
DISPLAY 1.446809 (425 -800);
PAINT MONO (425 -800);
DISPLAY INVISIBLE (425 -800);
FORCEPROP 2 LAST ROOM PVCCIN_CPU0_PWR_VR
J 0
(250 -800);
DISPLAY 1.936170 (250 -800);
PAINT ORANGE (250 -800);
DISPLAY INVISIBLE (250 -800);
FORCEPROP 1 LAST BODY_TYPE PLUMBING
J 0
(755 -918);
DISPLAY 0.340426 (755 -918);
PAINT GREEN (755 -918);
DISPLAY INVISIBLE (755 -918);
FORCEADD SC2K2P50V3KX-GP..1
(2800 -575);
FORCEPROP 1 LAST LOCATION CT33
J 0
(2825 -545);
DISPLAY 0.617021 (2825 -545);
PAINT GREEN (2825 -545);
FORCEPROP 0 LAST STATUS NOPOP
J 0
(2575 -550);
DISPLAY 1.021277 (2575 -550);
PAINT ORANGE (2575 -550);
FORCEPROP 1 LAST VALUE SC2K2P50V3KX-GP
J 0
(2825 -625);
DISPLAY 0.617021 (2825 -625);
PAINT GREEN (2825 -625);
FORCEPROP 1 LAST PACK_TYPE SMD-BCG6
J 0
(2800 -575);
DISPLAY 0.617021 (2800 -575);
PAINT GREEN (2800 -575);
DISPLAY INVISIBLE (2800 -575);
FORCEPROP 1 LAST PART_NUMBER 78.22224.2BL
J 0
(2800 -575);
DISPLAY 0.617021 (2800 -575);
PAINT GREEN (2800 -575);
DISPLAY INVISIBLE (2800 -575);
FORCEPROP 1 LAST CDS_LMAN_SYM_OUTLINE -50,25,50,-25
J 0
(2800 -575);
DISPLAY 0.468085 (2800 -575);
PAINT GREEN (2800 -575);
DISPLAY INVISIBLE (2800 -575);
FORCEPROP 1 LAST PATH I127
J 0
(2800 -575);
DISPLAY 0.617021 (2800 -575);
PAINT GREEN (2800 -575);
DISPLAY INVISIBLE (2800 -575);
FORCEPROP 2 LAST CDS_LIB w_hdl
J 0
(2800 -575);
PAINT MONO (2800 -575);
DISPLAY INVISIBLE (2800 -575);
FORCEADD GND..1
(2800 -1100);
FORCEPROP 3 LASTPIN (2800 -1050) SIG_NAME GND\g
J 0
(2810 -1040);
DISPLAY 0.659574 (2810 -1040);
PAINT MONO (2810 -1040);
DISPLAY INVISIBLE (2810 -1040);
FORCEPROP 2 LAST CDS_LIB mstr_symbols
J 0
(2800 -1100);
PAINT MONO (2800 -1100);
DISPLAY INVISIBLE (2800 -1100);
FORCEPROP 1 LAST PATH I128
J 0
(2875 -1100);
DISPLAY 0.872340 (2875 -1100);
PAINT AQUA (2875 -1100);
DISPLAY INVISIBLE (2875 -1100);
FORCEPROP 2 LAST ROOM PVCCIN_CPU0_PWR_VR
J 0
(2250 -1025);
DISPLAY 1.936170 (2250 -1025);
PAINT ORANGE (2250 -1025);
DISPLAY INVISIBLE (2250 -1025);
FORCEPROP 2 LAST BOM_COST PROC_VRD_VCCIN_CPU0
J 0
(2425 -1025);
DISPLAY 1.446809 (2425 -1025);
PAINT MONO (2425 -1025);
DISPLAY INVISIBLE (2425 -1025);
FORCEPROP 1 LAST BODY_TYPE PLUMBING
J 0
(2755 -1143);
DISPLAY 0.340426 (2755 -1143);
PAINT GREEN (2755 -1143);
DISPLAY INVISIBLE (2755 -1143);
FORCEPROP 1 LAST VOLTAGE 0
J 0
(2800 -1100);
PAINT SKYBLUE (2800 -1100);
DISPLAY INVISIBLE (2800 -1100);
FORCEPROP 1 LAST SIZE 1B
J 0
(2875 -1150);
DISPLAY 1.723404 (2875 -1150);
PAINT GREEN (2875 -1150);
DISPLAY INVISIBLE (2875 -1150);
FORCEPROP 1 LAST HDL_POWER GND
J 0
(2800 -950);
DISPLAY 1.723404 (2800 -950);
PAINT GREEN (2800 -950);
DISPLAY INVISIBLE (2800 -950);
FORCEADD 3D01R5F-GP..1
R 4
(2800 -875);
FORCEPROP 1 LAST VALUE 3D01R5F-GP
J 0
(2550 -950);
DISPLAY 0.617021 (2550 -950);
PAINT GREEN (2550 -950);
FORCEPROP 0 LAST STATUS NOPOP
J 0
(2550 -850);
DISPLAY 1.021277 (2550 -850);
PAINT ORANGE (2550 -850);
FORCEPROP 1 LAST LOCATION RT22
J 0
(2675 -905);
DISPLAY 0.617021 (2675 -905);
PAINT GREEN (2675 -905);
FORCEPROP 2 LASTPIN (2800 -750) SIG_NAME UN$224$3D01R5F-GP$I129$2
J 0
(2810 -740);
DISPLAY 0.659574 (2810 -740);
PAINT MONO (2810 -740);
DISPLAY INVISIBLE (2810 -740);
FORCEPROP 1 LAST PACK_TYPE SMD-RG5
R 2
J 0
(2800 -875);
DISPLAY 0.617021 (2800 -875);
PAINT GREEN (2800 -875);
DISPLAY INVISIBLE (2800 -875);
FORCEPROP 1 LAST PART_NUMBER 64.3R015.16L
R 2
J 0
(2800 -875);
DISPLAY 0.617021 (2800 -875);
PAINT GREEN (2800 -875);
DISPLAY INVISIBLE (2800 -875);
FORCEPROP 2 LAST CDS_LIB w_hdl
J 0
(2800 -875);
PAINT MONO (2800 -875);
DISPLAY INVISIBLE (2800 -875);
FORCEPROP 1 LAST PATH I129
R 2
J 0
(2800 -875);
DISPLAY 0.617021 (2800 -875);
PAINT GREEN (2800 -875);
DISPLAY INVISIBLE (2800 -875);
FORCEPROP 1 LAST CDS_LMAN_SYM_OUTLINE -50,75,50,-75
R 2
J 0
(2800 -875);
DISPLAY 0.468085 (2800 -875);
PAINT GREEN (2800 -875);
DISPLAY INVISIBLE (2800 -875);
FORCEADD CAP..1
(2700 -75);
FORCEPROP 1 LAST VALUE 1000PF
J 0
(2750 -25);
DISPLAY 0.617021 (2750 -25);
PAINT SKYBLUE (2750 -25);
FORCEPROP 1 LAST MATERIAL X7R
J 0
(2750 -175);
DISPLAY 0.617021 (2750 -175);
PAINT SKYBLUE (2750 -175);
FORCEPROP 1 LAST TOLERANCE 10%
J 0
(2750 -125);
DISPLAY 0.617021 (2750 -125);
PAINT SKYBLUE (2750 -125);
FORCEPROP 1 LAST LOCATION CT32
J 0
(2550 -75);
DISPLAY 0.617021 (2550 -75);
PAINT AQUA (2550 -75);
FORCEPROP 0 LAST STATUS NOPOP
J 0
(2475 -25);
DISPLAY 1.021277 (2475 -25);
PAINT ORANGE (2475 -25);
FORCEPROP 1 LAST VOLTAGE 50V
J 0
(2750 -75);
DISPLAY 0.617021 (2750 -75);
PAINT SKYBLUE (2750 -75);
FORCEPROP 1 LAST PART_NUMBER A36096-046
J 0
(2750 -225);
DISPLAY 0.617021 (2750 -225);
PAINT BLUE (2750 -225);
FORCEPROP 1 LAST PACK_TYPE 0402LF
J 0
(2750 -275);
DISPLAY 0.617021 (2750 -275);
PAINT SKYBLUE (2750 -275);
FORCEPROP 0 LAST ROOM VDDQ_KLM_PWR_VR
J 0
(2750 125);
DISPLAY 1.021277 (2750 125);
PAINT ORANGE (2750 125);
DISPLAY INVISIBLE (2750 125);
FORCEPROP 1 LAST PATH I130
J 0
(2750 75);
DISPLAY 0.978723 (2750 75);
PAINT WHITE (2750 75);
DISPLAY INVISIBLE (2750 75);
FORCEPROP 2 LAST CDS_LIB mstr_discrete
J 0
(2700 -75);
PAINT MONO (2700 -75);
DISPLAY INVISIBLE (2700 -75);
FORCEPROP 1 LASTPIN (2700 -175) $PN 2
J 0
(2710 -195);
DISPLAY 0.787234 (2710 -195);
PAINT ORANGE (2710 -195);
DISPLAY INVISIBLE (2710 -195);
FORCEPROP 1 LASTPIN (2700 25) $PN 1
J 0
(2710 5);
DISPLAY 0.787234 (2710 5);
PAINT ORANGE (2710 5);
DISPLAY INVISIBLE (2710 5);
FORCEADD GND..1
(2700 -300);
FORCEPROP 3 LASTPIN (2700 -250) SIG_NAME GND\g
J 0
(2710 -240);
DISPLAY 0.659574 (2710 -240);
PAINT MONO (2710 -240);
DISPLAY INVISIBLE (2710 -240);
FORCEPROP 1 LAST HDL_POWER GND
J 0
(2700 -150);
DISPLAY 1.170213 (2700 -150);
PAINT GREEN (2700 -150);
DISPLAY INVISIBLE (2700 -150);
FORCEPROP 1 LAST SIZE 1B
J 0
(2775 -350);
DISPLAY 1.170213 (2775 -350);
PAINT AQUA (2775 -350);
DISPLAY INVISIBLE (2775 -350);
FORCEPROP 1 LAST BODY_TYPE PLUMBING
J 0
(2655 -343);
DISPLAY 0.340426 (2655 -343);
PAINT GREEN (2655 -343);
DISPLAY INVISIBLE (2655 -343);
FORCEPROP 1 LAST VOLTAGE 0
J 0
(2700 -300);
PAINT SKYBLUE (2700 -300);
DISPLAY INVISIBLE (2700 -300);
FORCEPROP 2 LAST ROOM VDDQ_KLM_PWR_VR
J 0
(2125 -225);
DISPLAY 1.361702 (2125 -225);
PAINT ORANGE (2125 -225);
DISPLAY INVISIBLE (2125 -225);
FORCEPROP 1 LAST PATH I131
J 0
(2775 -300);
DISPLAY 0.872340 (2775 -300);
PAINT AQUA (2775 -300);
DISPLAY INVISIBLE (2775 -300);
FORCEPROP 2 LAST CDS_LIB mstr_symbols
J 0
(2700 -300);
PAINT MONO (2700 -300);
DISPLAY INVISIBLE (2700 -300);
FORCEADD RES..1
(-275 2000);
FORCEPROP 1 LAST PART_NUMBER G21497-005
J 0
(-375 1950);
DISPLAY 0.617021 (-375 1950);
PAINT BLUE (-375 1950);
FORCEPROP 1 LAST VALUE 0.0
J 2
(-300 1900);
DISPLAY 0.617021 (-300 1900);
PAINT SKYBLUE (-300 1900);
FORCEPROP 1 LAST TOLERANCE 5%
J 0
(-275 1900);
DISPLAY 0.617021 (-275 1900);
PAINT SKYBLUE (-275 1900);
FORCEPROP 1 LAST MATERIAL CHIP
J 0
(-275 1850);
DISPLAY 0.617021 (-275 1850);
PAINT SKYBLUE (-275 1850);
FORCEPROP 1 LAST PACK_TYPE 0402
J 0
(-175 1850);
DISPLAY 0.617021 (-175 1850);
PAINT SKYBLUE (-175 1850);
FORCEPROP 1 LAST WATTAGE 1/16W
J 2
(-300 1850);
DISPLAY 0.617021 (-300 1850);
PAINT SKYBLUE (-300 1850);
FORCEPROP 1 LAST LOCATION RT19
J 0
(-325 2025);
DISPLAY 0.617021 (-325 2025);
PAINT AQUA (-325 2025);
FORCEPROP 2 LAST ROOM BMC_DEBUG_HEADER
J 0
(-325 2150);
DISPLAY 1.021277 (-325 2150);
PAINT ORANGE (-325 2150);
DISPLAY INVISIBLE (-325 2150);
FORCEPROP 2 LAST BOM_COST DEBUG
J 0
(-325 2200);
DISPLAY 1.021277 (-325 2200);
PAINT ORANGE (-325 2200);
DISPLAY INVISIBLE (-325 2200);
FORCEPROP 1 LAST PATH I132
J 0
(-325 2150);
DISPLAY 0.978723 (-325 2150);
PAINT WHITE (-325 2150);
DISPLAY INVISIBLE (-325 2150);
FORCEPROP 2 LAST CDS_LIB mstr_discrete
J 0
(-275 2000);
PAINT MONO (-275 2000);
DISPLAY INVISIBLE (-275 2000);
FORCEPROP 1 LASTPIN (-375 2000) $PN 1
J 0
(-363 2012);
DISPLAY 0.787234 (-363 2012);
PAINT ORANGE (-363 2012);
DISPLAY INVISIBLE (-363 2012);
FORCEPROP 1 LASTPIN (-175 2000) $PN 2
J 0
(-213 2012);
DISPLAY 0.787234 (-213 2012);
PAINT ORANGE (-213 2012);
DISPLAY INVISIBLE (-213 2012);
FORCEADD RES..1
(50 -325);
FORCEPROP 1 LAST MATERIAL CHIP
J 0
(-25 -475);
DISPLAY 0.617021 (-25 -475);
PAINT SKYBLUE (-25 -475);
FORCEPROP 1 LAST TOLERANCE 5%
J 0
(50 -425);
DISPLAY 0.617021 (50 -425);
PAINT SKYBLUE (50 -425);
FORCEPROP 1 LAST PACK_TYPE 0402
J 0
(75 -475);
DISPLAY 0.617021 (75 -475);
PAINT SKYBLUE (75 -475);
FORCEPROP 1 LAST WATTAGE 1/16W
J 2
(-25 -475);
DISPLAY 0.617021 (-25 -475);
PAINT SKYBLUE (-25 -475);
FORCEPROP 1 LAST PART_NUMBER G21497-005
J 0
(-100 -375);
DISPLAY 0.617021 (-100 -375);
PAINT BLUE (-100 -375);
FORCEPROP 1 LAST VALUE 0.0
J 2
(25 -425);
DISPLAY 0.617021 (25 -425);
PAINT SKYBLUE (25 -425);
FORCEPROP 1 LAST LOCATION RT21
J 0
(0 -300);
DISPLAY 0.617021 (0 -300);
PAINT AQUA (0 -300);
FORCEPROP 2 LAST ROOM BMC_DEBUG_HEADER
J 0
(0 -175);
DISPLAY 1.021277 (0 -175);
PAINT ORANGE (0 -175);
DISPLAY INVISIBLE (0 -175);
FORCEPROP 2 LAST BOM_COST DEBUG
J 0
(0 -125);
DISPLAY 1.021277 (0 -125);
PAINT ORANGE (0 -125);
DISPLAY INVISIBLE (0 -125);
FORCEPROP 1 LAST PATH I133
J 0
(0 -175);
DISPLAY 0.978723 (0 -175);
PAINT WHITE (0 -175);
DISPLAY INVISIBLE (0 -175);
FORCEPROP 2 LAST CDS_LIB mstr_discrete
J 0
(50 -325);
PAINT MONO (50 -325);
DISPLAY INVISIBLE (50 -325);
FORCEPROP 1 LASTPIN (-50 -325) $PN 1
J 0
(-38 -313);
DISPLAY 0.787234 (-38 -313);
PAINT ORANGE (-38 -313);
DISPLAY INVISIBLE (-38 -313);
FORCEPROP 1 LASTPIN (150 -325) $PN 2
J 0
(112 -313);
DISPLAY 0.787234 (112 -313);
PAINT ORANGE (112 -313);
DISPLAY INVISIBLE (112 -313);
FORCEADD GND..1
(2325 1500);
FORCEPROP 3 LASTPIN (2325 1550) SIG_NAME GND\g
J 0
(2335 1560);
DISPLAY 0.659574 (2335 1560);
PAINT MONO (2335 1560);
DISPLAY INVISIBLE (2335 1560);
FORCEPROP 2 LAST ROOM VDDQ_GHJ_PWR_VR
J 0
(1775 1575);
DISPLAY 1.936170 (1775 1575);
PAINT ORANGE (1775 1575);
DISPLAY INVISIBLE (1775 1575);
FORCEPROP 2 LAST BOM_COST VDDQ_GHJ_PWR_VR
J 0
(1950 1575);
DISPLAY 1.446809 (1950 1575);
PAINT MONO (1950 1575);
DISPLAY INVISIBLE (1950 1575);
FORCEPROP 1 LAST SIZE 1B
J 0
(2400 1450);
DISPLAY 1.723404 (2400 1450);
PAINT GREEN (2400 1450);
DISPLAY INVISIBLE (2400 1450);
FORCEPROP 1 LAST BODY_TYPE PLUMBING
J 0
(2280 1457);
DISPLAY 0.340426 (2280 1457);
PAINT GREEN (2280 1457);
DISPLAY INVISIBLE (2280 1457);
FORCEPROP 1 LAST VOLTAGE 0
J 0
(2325 1500);
PAINT SKYBLUE (2325 1500);
DISPLAY INVISIBLE (2325 1500);
FORCEPROP 2 LAST CDS_LIB mstr_symbols
J 0
(2325 1500);
DISPLAY 1.936170 (2325 1500);
PAINT ORANGE (2325 1500);
DISPLAY INVISIBLE (2325 1500);
FORCEPROP 1 LAST PATH I19
J 0
(2400 1500);
DISPLAY 0.893617 (2400 1500);
PAINT AQUA (2400 1500);
DISPLAY INVISIBLE (2400 1500);
FORCEPROP 1 LAST HDL_POWER GND
J 0
(2325 1650);
DISPLAY 1.723404 (2325 1650);
PAINT GREEN (2325 1650);
DISPLAY INVISIBLE (2325 1650);
FORCEADD OFFPAGE..2
(3325 2800);
FORCEPROP 2 LAST $XR0 223 
J 0
(3514 2800);
DISPLAY 0.638298 (3514 2800);
PAINT MONO (3514 2800);
FORCEPROP 2 LAST ROOM VDDQ_GHJ_PWR_VR
J 0
(2925 2875);
DISPLAY 1.936170 (2925 2875);
PAINT ORANGE (2925 2875);
DISPLAY INVISIBLE (2925 2875);
FORCEPROP 1 LAST COMMENT_BODY TRUE
J 0
(3280 2705);
DISPLAY 1.723404 (3280 2705);
PAINT GREEN (3280 2705);
DISPLAY INVISIBLE (3280 2705);
FORCEPROP 2 LAST CDS_LIB mstr_standard
J 0
(3325 2800);
DISPLAY 1.936170 (3325 2800);
PAINT ORANGE (3325 2800);
DISPLAY INVISIBLE (3325 2800);
FORCEPROP 2 LAST PATH I3
J 0
(3515 2850);
DISPLAY 1.021277 (3515 2850);
PAINT ORANGE (3515 2850);
DISPLAY INVISIBLE (3515 2850);
FORCEPROP 2 LAST BOM_COST VDDQ_GHJ_PWR_VR
J 0
(3525 2850);
DISPLAY 1.446809 (3525 2850);
PAINT MONO (3525 2850);
DISPLAY INVISIBLE (3525 2850);
FORCEPROP 1 LAST OFFPAGE TRUE
J 0
(3650 2675);
DISPLAY 1.723404 (3650 2675);
PAINT GREEN (3650 2675);
DISPLAY INVISIBLE (3650 2675);
FORCEADD OFFPAGE..1
(-2050 2150);
FORCEPROP 2 LAST $XR0 223 
J 0
(-2302 2150);
DISPLAY 0.638298 (-2302 2150);
PAINT MONO (-2302 2150);
FORCEPROP 2 LASTPIN (-2000 2150) SIG_NAME VR_PVDDQ_GHJ_PWM1
J 0
(-1985 2160);
DISPLAY 0.617021 (-1985 2160);
PAINT ORANGE (-1985 2160);
FORCEPROP 2 LAST PATH I33
J 0
(-2330 2200);
DISPLAY 1.021277 (-2330 2200);
PAINT ORANGE (-2330 2200);
DISPLAY INVISIBLE (-2330 2200);
FORCEPROP 2 LAST ROOM VDDQ_GHJ_PWR_VR
J 0
(-2450 2225);
DISPLAY 1.936170 (-2450 2225);
PAINT ORANGE (-2450 2225);
DISPLAY INVISIBLE (-2450 2225);
FORCEPROP 2 LAST BOM_COST VDDQ_GHJ_PWR_VR
J 0
(-2300 2200);
DISPLAY 1.446809 (-2300 2200);
PAINT MONO (-2300 2200);
DISPLAY INVISIBLE (-2300 2200);
FORCEPROP 2 LAST CDS_LIB mstr_standard
J 0
(-2050 2150);
DISPLAY 1.936170 (-2050 2150);
PAINT ORANGE (-2050 2150);
DISPLAY INVISIBLE (-2050 2150);
FORCEPROP 1 LAST OFFPAGE TRUE
J 0
(-1725 2025);
DISPLAY 1.680851 (-1725 2025);
PAINT GREEN (-1725 2025);
DISPLAY INVISIBLE (-1725 2025);
FORCEPROP 1 LAST COMMENT_BODY TRUE
J 0
(-1925 2050);
DISPLAY 1.680851 (-1925 2050);
PAINT GREEN (-1925 2050);
DISPLAY INVISIBLE (-1925 2050);
FORCEADD GND..1
(-2700 2075);
FORCEPROP 3 LASTPIN (-2700 2125) SIG_NAME GND\g
J 0
(-2690 2135);
DISPLAY 0.659574 (-2690 2135);
PAINT MONO (-2690 2135);
DISPLAY INVISIBLE (-2690 2135);
FORCEPROP 1 LAST BODY_TYPE PLUMBING
J 0
(-2745 2032);
DISPLAY 0.340426 (-2745 2032);
PAINT GREEN (-2745 2032);
DISPLAY INVISIBLE (-2745 2032);
FORCEPROP 1 LAST SIZE 1B
J 0
(-2625 2025);
DISPLAY 1.723404 (-2625 2025);
PAINT GREEN (-2625 2025);
DISPLAY INVISIBLE (-2625 2025);
FORCEPROP 2 LAST ROOM VDDQ_GHJ_PWR_VR
J 0
(-3250 2150);
DISPLAY 1.936170 (-3250 2150);
PAINT ORANGE (-3250 2150);
DISPLAY INVISIBLE (-3250 2150);
FORCEPROP 2 LAST BOM_COST VDDQ_GHJ_PWR_VR
J 0
(-3075 2150);
DISPLAY 1.446809 (-3075 2150);
PAINT MONO (-3075 2150);
DISPLAY INVISIBLE (-3075 2150);
FORCEPROP 1 LAST VOLTAGE 0
J 0
(-2700 2075);
PAINT SKYBLUE (-2700 2075);
DISPLAY INVISIBLE (-2700 2075);
FORCEPROP 2 LAST CDS_LIB mstr_symbols
J 0
(-2700 2075);
DISPLAY 1.936170 (-2700 2075);
PAINT ORANGE (-2700 2075);
DISPLAY INVISIBLE (-2700 2075);
FORCEPROP 1 LAST HDL_POWER GND
J 0
(-2700 2225);
DISPLAY 1.723404 (-2700 2225);
PAINT GREEN (-2700 2225);
DISPLAY INVISIBLE (-2700 2225);
FORCEPROP 1 LAST PATH I35
J 0
(-2625 2075);
DISPLAY 0.893617 (-2625 2075);
PAINT AQUA (-2625 2075);
DISPLAY INVISIBLE (-2625 2075);
FORCEADD OFFPAGE..2
(3400 3150);
FORCEPROP 2 LAST $XR0 223 
J 0
(3589 3150);
DISPLAY 0.638298 (3589 3150);
PAINT MONO (3589 3150);
FORCEPROP 2 LAST ROOM VDDQ_GHJ_PWR_VR
J 0
(3000 3225);
DISPLAY 1.936170 (3000 3225);
PAINT ORANGE (3000 3225);
DISPLAY INVISIBLE (3000 3225);
FORCEPROP 1 LAST COMMENT_BODY TRUE
J 0
(3355 3055);
DISPLAY 1.723404 (3355 3055);
PAINT GREEN (3355 3055);
DISPLAY INVISIBLE (3355 3055);
FORCEPROP 1 LAST OFFPAGE TRUE
J 0
(3725 3025);
DISPLAY 1.723404 (3725 3025);
PAINT GREEN (3725 3025);
DISPLAY INVISIBLE (3725 3025);
FORCEPROP 2 LAST CDS_LIB mstr_standard
J 2
(3400 3150);
DISPLAY 1.936170 (3400 3150);
PAINT ORANGE (3400 3150);
DISPLAY INVISIBLE (3400 3150);
FORCEPROP 2 LAST PATH I4
J 0
(3590 3200);
DISPLAY 1.021277 (3590 3200);
PAINT ORANGE (3590 3200);
DISPLAY INVISIBLE (3590 3200);
FORCEPROP 2 LAST BOM_COST VDDQ_GHJ_PWR_VR
J 0
(3600 3200);
DISPLAY 1.446809 (3600 3200);
PAINT MONO (3600 3200);
DISPLAY INVISIBLE (3600 3200);
FORCEADD CAP..1
R 2
(-1125 1900);
FORCEPROP 1 LAST TOLERANCE 10%
J 2
(-1175 1850);
DISPLAY 0.617021 (-1175 1850);
PAINT SKYBLUE (-1175 1850);
FORCEPROP 1 LAST VOLTAGE 16V
J 2
(-1175 1900);
DISPLAY 0.617021 (-1175 1900);
PAINT SKYBLUE (-1175 1900);
FORCEPROP 1 LASTPIN (-1125 2000) $PN 1
J 2
(-1135 1980);
DISPLAY 0.617021 (-1135 1980);
PAINT ORANGE (-1135 1980);
FORCEPROP 1 LASTPIN (-1125 1800) $PN 2
J 2
(-1135 1780);
DISPLAY 0.617021 (-1135 1780);
PAINT ORANGE (-1135 1780);
FORCEPROP 1 LAST LOCATION C1G11
J 2
(-1175 2000);
DISPLAY 0.617021 (-1175 2000);
PAINT AQUA (-1175 2000);
FORCEPROP 1 LAST PART_NUMBER A36096-104
J 2
(-1175 1750);
DISPLAY 0.617021 (-1175 1750);
PAINT BLUE (-1175 1750);
FORCEPROP 1 LAST VALUE 0.220UF
J 2
(-1175 1950);
DISPLAY 0.617021 (-1175 1950);
PAINT SKYBLUE (-1175 1950);
FORCEPROP 1 LAST PACK_TYPE 0402
J 2
(-1175 1700);
DISPLAY 0.617021 (-1175 1700);
PAINT SKYBLUE (-1175 1700);
FORCEPROP 1 LAST MATERIAL X7R
J 2
(-1175 1800);
DISPLAY 0.617021 (-1175 1800);
PAINT SKYBLUE (-1175 1800);
FORCEPROP 2 LAST CDS_LIB mstr_discrete
J 0
(-1125 1900);
PAINT ORANGE (-1125 1900);
DISPLAY INVISIBLE (-1125 1900);
FORCEPROP 0 LAST SPOF TRUE
J 0
(-1175 2100);
DISPLAY 1.021277 (-1175 2100);
PAINT ORANGE (-1175 2100);
DISPLAY INVISIBLE (-1175 2100);
FORCEPROP 2 LAST SEC_TYPE 0402
J 0
(-1175 2100);
DISPLAY 1.021277 (-1175 2100);
PAINT ORANGE (-1175 2100);
DISPLAY INVISIBLE (-1175 2100);
FORCEPROP 2 LAST SEC 1
J 0
(-1175 2100);
DISPLAY 0.680851 (-1175 2100);
PAINT MONO (-1175 2100);
DISPLAY INVISIBLE (-1175 2100);
FORCEPROP 2 LAST CDS_LOCATION C1G11
J 2
(-1175 2000);
DISPLAY 0.617021 (-1175 2000);
PAINT AQUA (-1175 2000);
DISPLAY INVISIBLE (-1175 2000);
FORCEPROP 1 LAST PATH I44
J 2
(-1175 2050);
DISPLAY 0.978723 (-1175 2050);
PAINT WHITE (-1175 2050);
DISPLAY INVISIBLE (-1175 2050);
FORCEPROP 2 LAST ROOM VDDQ_GHJ_PWR_VR
J 0
(-1200 2050);
DISPLAY 1.361702 (-1200 2050);
PAINT ORANGE (-1200 2050);
DISPLAY INVISIBLE (-1200 2050);
FORCEADD CAP..1
(-2700 2525);
FORCEPROP 1 LASTPIN (-2700 2425) $PN 2
J 0
(-2690 2405);
DISPLAY 0.617021 (-2690 2405);
PAINT ORANGE (-2690 2405);
FORCEPROP 1 LAST MATERIAL X6S
J 0
(-2650 2425);
DISPLAY 0.617021 (-2650 2425);
PAINT SKYBLUE (-2650 2425);
FORCEPROP 1 LAST VOLTAGE 16V
J 0
(-2650 2525);
DISPLAY 0.617021 (-2650 2525);
PAINT SKYBLUE (-2650 2525);
FORCEPROP 1 LAST TOLERANCE 10%
J 0
(-2650 2475);
DISPLAY 0.617021 (-2650 2475);
PAINT SKYBLUE (-2650 2475);
FORCEPROP 1 LASTPIN (-2700 2625) $PN 1
J 0
(-2690 2605);
DISPLAY 0.617021 (-2690 2605);
PAINT ORANGE (-2690 2605);
FORCEPROP 1 LAST PACK_TYPE 0805
J 0
(-2650 2325);
DISPLAY 0.617021 (-2650 2325);
PAINT SKYBLUE (-2650 2325);
FORCEPROP 1 LAST VALUE 10UF
J 0
(-2650 2575);
DISPLAY 0.617021 (-2650 2575);
PAINT SKYBLUE (-2650 2575);
FORCEPROP 1 LAST PART_NUMBER C95333-007
J 0
(-2650 2375);
DISPLAY 0.617021 (-2650 2375);
PAINT BLUE (-2650 2375);
FORCEPROP 1 LAST LOCATION C9U6
J 0
(-2650 2625);
DISPLAY 0.617021 (-2650 2625);
PAINT AQUA (-2650 2625);
FORCEPROP 2 LAST CDS_LIB mstr_discrete
J 0
(-2700 2525);
PAINT ORANGE (-2700 2525);
DISPLAY INVISIBLE (-2700 2525);
FORCEPROP 2 LAST ROOM VDDQ_GHJ_PWR_VR
J 0
(-2650 2675);
DISPLAY 1.361702 (-2650 2675);
PAINT ORANGE (-2650 2675);
DISPLAY INVISIBLE (-2650 2675);
FORCEPROP 1 LAST PATH I45
J 0
(-2650 2675);
DISPLAY 1.319149 (-2650 2675);
PAINT WHITE (-2650 2675);
DISPLAY INVISIBLE (-2650 2675);
FORCEPROP 2 LAST CDS_LOCATION C9U6
J 0
(-2650 2625);
DISPLAY 0.617021 (-2650 2625);
PAINT AQUA (-2650 2625);
DISPLAY INVISIBLE (-2650 2625);
FORCEPROP 2 LAST SEC 1
J 0
(-2650 2750);
DISPLAY 0.680851 (-2650 2750);
PAINT MONO (-2650 2750);
DISPLAY INVISIBLE (-2650 2750);
FORCEPROP 2 LAST SEC_TYPE 0805
J 0
(-2650 2750);
DISPLAY 1.021277 (-2650 2750);
PAINT ORANGE (-2650 2750);
DISPLAY INVISIBLE (-2650 2750);
FORCEADD CAP..1
(-2450 2550);
FORCEPROP 1 LAST TOLERANCE 10%
J 0
(-2400 2500);
DISPLAY 0.617021 (-2400 2500);
PAINT SKYBLUE (-2400 2500);
FORCEPROP 1 LAST MATERIAL X6S
J 0
(-2400 2450);
DISPLAY 0.617021 (-2400 2450);
PAINT SKYBLUE (-2400 2450);
FORCEPROP 1 LASTPIN (-2450 2450) $PN 2
J 0
(-2440 2430);
DISPLAY 0.617021 (-2440 2430);
PAINT ORANGE (-2440 2430);
FORCEPROP 1 LAST PACK_TYPE 0805
J 0
(-2400 2350);
DISPLAY 0.617021 (-2400 2350);
PAINT SKYBLUE (-2400 2350);
FORCEPROP 1 LAST PART_NUMBER C95333-007
J 0
(-2400 2400);
DISPLAY 0.617021 (-2400 2400);
PAINT BLUE (-2400 2400);
FORCEPROP 1 LAST VOLTAGE 16V
J 0
(-2400 2550);
DISPLAY 0.617021 (-2400 2550);
PAINT SKYBLUE (-2400 2550);
FORCEPROP 1 LASTPIN (-2450 2650) $PN 1
J 0
(-2440 2630);
DISPLAY 0.617021 (-2440 2630);
PAINT ORANGE (-2440 2630);
FORCEPROP 1 LAST LOCATION C9U4
J 0
(-2400 2650);
DISPLAY 0.617021 (-2400 2650);
PAINT AQUA (-2400 2650);
FORCEPROP 1 LAST VALUE 10UF
J 0
(-2400 2600);
DISPLAY 0.617021 (-2400 2600);
PAINT SKYBLUE (-2400 2600);
FORCEPROP 2 LAST CDS_LIB mstr_discrete
J 0
(-2450 2550);
PAINT ORANGE (-2450 2550);
DISPLAY INVISIBLE (-2450 2550);
FORCEPROP 2 LAST ROOM VDDQ_GHJ_PWR_VR
J 0
(-2400 2700);
DISPLAY 1.361702 (-2400 2700);
PAINT ORANGE (-2400 2700);
DISPLAY INVISIBLE (-2400 2700);
FORCEPROP 1 LAST PATH I46
J 0
(-2400 2700);
DISPLAY 1.319149 (-2400 2700);
PAINT WHITE (-2400 2700);
DISPLAY INVISIBLE (-2400 2700);
FORCEPROP 2 LAST CDS_LOCATION C9U4
J 0
(-2400 2650);
DISPLAY 0.617021 (-2400 2650);
PAINT AQUA (-2400 2650);
DISPLAY INVISIBLE (-2400 2650);
FORCEPROP 2 LAST SEC 1
J 0
(-2400 2775);
DISPLAY 0.680851 (-2400 2775);
PAINT MONO (-2400 2775);
DISPLAY INVISIBLE (-2400 2775);
FORCEPROP 2 LAST SEC_TYPE 0805
J 0
(-2400 2775);
DISPLAY 1.021277 (-2400 2775);
PAINT ORANGE (-2400 2775);
DISPLAY INVISIBLE (-2400 2775);
FORCEADD CAP..1
(-2175 2550);
FORCEPROP 1 LASTPIN (-2175 2450) $PN 2
J 0
(-2165 2430);
DISPLAY 0.617021 (-2165 2430);
PAINT ORANGE (-2165 2430);
FORCEPROP 1 LASTPIN (-2175 2650) $PN 1
J 0
(-2165 2630);
DISPLAY 0.617021 (-2165 2630);
PAINT ORANGE (-2165 2630);
FORCEPROP 1 LAST MATERIAL X6S
J 0
(-2125 2450);
DISPLAY 0.617021 (-2125 2450);
PAINT SKYBLUE (-2125 2450);
FORCEPROP 1 LAST VOLTAGE 16V
J 0
(-2125 2550);
DISPLAY 0.617021 (-2125 2550);
PAINT SKYBLUE (-2125 2550);
FORCEPROP 1 LAST TOLERANCE 10%
J 0
(-2125 2500);
DISPLAY 0.617021 (-2125 2500);
PAINT SKYBLUE (-2125 2500);
FORCEPROP 1 LAST VALUE 10UF
J 0
(-2125 2600);
DISPLAY 0.617021 (-2125 2600);
PAINT SKYBLUE (-2125 2600);
FORCEPROP 1 LAST PART_NUMBER C95333-007
J 0
(-2125 2400);
DISPLAY 0.617021 (-2125 2400);
PAINT BLUE (-2125 2400);
FORCEPROP 1 LAST LOCATION C9T4
J 0
(-2125 2650);
DISPLAY 0.617021 (-2125 2650);
PAINT AQUA (-2125 2650);
FORCEPROP 1 LAST PACK_TYPE 0805
J 0
(-2125 2350);
DISPLAY 0.617021 (-2125 2350);
PAINT SKYBLUE (-2125 2350);
FORCEPROP 2 LAST CDS_LIB mstr_discrete
J 0
(-2175 2550);
PAINT ORANGE (-2175 2550);
DISPLAY INVISIBLE (-2175 2550);
FORCEPROP 2 LAST SEC 1
J 0
(-2125 2775);
DISPLAY 0.680851 (-2125 2775);
PAINT MONO (-2125 2775);
DISPLAY INVISIBLE (-2125 2775);
FORCEPROP 2 LAST CDS_LOCATION C9T4
J 0
(-2125 2650);
DISPLAY 0.617021 (-2125 2650);
PAINT AQUA (-2125 2650);
DISPLAY INVISIBLE (-2125 2650);
FORCEPROP 1 LAST PATH I47
J 0
(-2125 2700);
DISPLAY 1.319149 (-2125 2700);
PAINT WHITE (-2125 2700);
DISPLAY INVISIBLE (-2125 2700);
FORCEPROP 2 LAST ROOM VDDQ_GHJ_PWR_VR
J 0
(-2125 2700);
DISPLAY 1.361702 (-2125 2700);
PAINT ORANGE (-2125 2700);
DISPLAY INVISIBLE (-2125 2700);
FORCEPROP 2 LAST SEC_TYPE 0805
J 0
(-2125 2775);
DISPLAY 1.021277 (-2125 2775);
PAINT ORANGE (-2125 2775);
DISPLAY INVISIBLE (-2125 2775);
FORCEADD CAP..1
(-1925 2450);
FORCEPROP 1 LASTPIN (-1925 2350) $PN 2
J 0
(-1915 2330);
DISPLAY 0.617021 (-1915 2330);
PAINT ORANGE (-1915 2330);
FORCEPROP 1 LASTPIN (-1925 2550) $PN 1
J 0
(-1915 2530);
DISPLAY 0.617021 (-1915 2530);
PAINT ORANGE (-1915 2530);
FORCEPROP 1 LAST MATERIAL X6S
J 0
(-1875 2350);
DISPLAY 0.617021 (-1875 2350);
PAINT SKYBLUE (-1875 2350);
FORCEPROP 1 LAST VOLTAGE 16V
J 0
(-1875 2450);
DISPLAY 0.617021 (-1875 2450);
PAINT SKYBLUE (-1875 2450);
FORCEPROP 1 LAST PACK_TYPE 0402
J 0
(-1875 2250);
DISPLAY 0.617021 (-1875 2250);
PAINT SKYBLUE (-1875 2250);
FORCEPROP 1 LAST TOLERANCE 10%
J 0
(-1875 2400);
DISPLAY 0.617021 (-1875 2400);
PAINT SKYBLUE (-1875 2400);
FORCEPROP 1 LAST VALUE 1.0UF
J 0
(-1875 2500);
DISPLAY 0.617021 (-1875 2500);
PAINT SKYBLUE (-1875 2500);
FORCEPROP 1 LAST PART_NUMBER D97712-011
J 0
(-1875 2300);
DISPLAY 0.617021 (-1875 2300);
PAINT BLUE (-1875 2300);
FORCEPROP 1 LAST LOCATION C1F27
J 0
(-1875 2550);
DISPLAY 0.617021 (-1875 2550);
PAINT AQUA (-1875 2550);
FORCEPROP 2 LAST CDS_LIB mstr_discrete
J 0
(-1925 2450);
PAINT ORANGE (-1925 2450);
DISPLAY INVISIBLE (-1925 2450);
FORCEPROP 2 LAST SEC_TYPE 0402
J 0
(-1875 2675);
DISPLAY 1.021277 (-1875 2675);
PAINT ORANGE (-1875 2675);
DISPLAY INVISIBLE (-1875 2675);
FORCEPROP 2 LAST SEC 1
J 0
(-1875 2675);
DISPLAY 0.680851 (-1875 2675);
PAINT MONO (-1875 2675);
DISPLAY INVISIBLE (-1875 2675);
FORCEPROP 1 LAST PATH I48
J 0
(-1875 2600);
DISPLAY 1.319149 (-1875 2600);
PAINT WHITE (-1875 2600);
DISPLAY INVISIBLE (-1875 2600);
FORCEPROP 2 LAST ROOM VDDQ_GHJ_PWR_VR
J 0
(-1875 2600);
DISPLAY 1.361702 (-1875 2600);
PAINT ORANGE (-1875 2600);
DISPLAY INVISIBLE (-1875 2600);
FORCEADD CAP..1
(-1375 2550);
FORCEPROP 1 LASTPIN (-1375 2450) $PN 2
J 0
(-1365 2430);
DISPLAY 0.617021 (-1365 2430);
PAINT ORANGE (-1365 2430);
FORCEPROP 1 LAST PART_NUMBER D97712-011
J 0
(-1325 2400);
DISPLAY 0.617021 (-1325 2400);
PAINT BLUE (-1325 2400);
FORCEPROP 1 LAST TOLERANCE 10%
J 0
(-1325 2500);
DISPLAY 0.617021 (-1325 2500);
PAINT SKYBLUE (-1325 2500);
FORCEPROP 1 LAST PACK_TYPE 0402
J 0
(-1325 2350);
DISPLAY 0.617021 (-1325 2350);
PAINT SKYBLUE (-1325 2350);
FORCEPROP 1 LAST MATERIAL X6S
J 0
(-1325 2450);
DISPLAY 0.617021 (-1325 2450);
PAINT SKYBLUE (-1325 2450);
FORCEPROP 1 LAST VOLTAGE 16V
J 0
(-1325 2550);
DISPLAY 0.617021 (-1325 2550);
PAINT SKYBLUE (-1325 2550);
FORCEPROP 1 LASTPIN (-1375 2650) $PN 1
J 0
(-1365 2630);
DISPLAY 0.617021 (-1365 2630);
PAINT ORANGE (-1365 2630);
FORCEPROP 1 LAST VALUE 1.0UF
J 0
(-1325 2600);
DISPLAY 0.617021 (-1325 2600);
PAINT SKYBLUE (-1325 2600);
FORCEPROP 1 LAST LOCATION C1G6
J 0
(-1325 2650);
DISPLAY 0.617021 (-1325 2650);
PAINT AQUA (-1325 2650);
FORCEPROP 2 LAST CDS_LIB mstr_discrete
J 0
(-1375 2550);
PAINT ORANGE (-1375 2550);
DISPLAY INVISIBLE (-1375 2550);
FORCEPROP 2 LAST CDS_LOCATION C1G6
J 0
(-1325 2650);
DISPLAY 0.617021 (-1325 2650);
PAINT AQUA (-1325 2650);
DISPLAY INVISIBLE (-1325 2650);
FORCEPROP 2 LAST SEC 1
J 0
(-1325 2775);
DISPLAY 0.680851 (-1325 2775);
PAINT MONO (-1325 2775);
DISPLAY INVISIBLE (-1325 2775);
FORCEPROP 1 LAST PATH I50
J 0
(-1325 2700);
DISPLAY 1.319149 (-1325 2700);
PAINT WHITE (-1325 2700);
DISPLAY INVISIBLE (-1325 2700);
FORCEPROP 2 LAST ROOM VDDQ_GHJ_PWR_VR
J 0
(-1325 2700);
DISPLAY 1.361702 (-1325 2700);
PAINT ORANGE (-1325 2700);
DISPLAY INVISIBLE (-1325 2700);
FORCEPROP 2 LAST SEC_TYPE 0402
J 0
(-1325 2775);
DISPLAY 1.021277 (-1325 2775);
PAINT ORANGE (-1325 2775);
DISPLAY INVISIBLE (-1325 2775);
FORCEADD CAP_A..1
(-1675 2500);
FORCEPROP 1 LAST TOLERANCE 10%
J 0
(-1625 2450);
DISPLAY 0.617021 (-1625 2450);
PAINT SKYBLUE (-1625 2450);
FORCEPROP 1 LAST VOLTAGE 16V
J 0
(-1625 2500);
DISPLAY 0.617021 (-1625 2500);
PAINT SKYBLUE (-1625 2500);
FORCEPROP 1 LAST MATERIAL X7R
J 0
(-1625 2400);
DISPLAY 0.617021 (-1625 2400);
PAINT SKYBLUE (-1625 2400);
FORCEPROP 1 LASTPIN (-1675 2400) $PN 2
J 0
(-1665 2380);
DISPLAY 0.617021 (-1665 2380);
PAINT ORANGE (-1665 2380);
FORCEPROP 1 LASTPIN (-1675 2600) $PN 1
J 0
(-1665 2580);
DISPLAY 0.617021 (-1665 2580);
PAINT ORANGE (-1665 2580);
FORCEPROP 1 LAST PACK_TYPE 0402V
J 0
(-1625 2300);
DISPLAY 0.617021 (-1625 2300);
PAINT SKYBLUE (-1625 2300);
FORCEPROP 1 LAST VALUE 0.1UF
J 0
(-1625 2550);
DISPLAY 0.617021 (-1625 2550);
PAINT SKYBLUE (-1625 2550);
FORCEPROP 1 LAST PART_NUMBER A36096-030
J 0
(-1625 2350);
DISPLAY 0.617021 (-1625 2350);
PAINT BLUE (-1625 2350);
FORCEPROP 1 LAST LOCATION C1G14
J 0
(-1625 2600);
DISPLAY 0.617021 (-1625 2600);
PAINT AQUA (-1625 2600);
FORCEPROP 2 LAST CDS_LIB dev_discrete
J 0
(-1675 2500);
PAINT ORANGE (-1675 2500);
DISPLAY INVISIBLE (-1675 2500);
FORCEPROP 1 LAST PATH I51
J 0
(-1625 2650);
DISPLAY 0.978723 (-1625 2650);
PAINT WHITE (-1625 2650);
DISPLAY INVISIBLE (-1625 2650);
FORCEPROP 2 LAST ROOM VDDQ_GHJ_PWR_VR
J 0
(-1625 2650);
DISPLAY 1.361702 (-1625 2650);
PAINT ORANGE (-1625 2650);
DISPLAY INVISIBLE (-1625 2650);
FORCEPROP 2 LAST CDS_LOCATION C1G14
J 0
(-1625 2600);
DISPLAY 0.617021 (-1625 2600);
PAINT AQUA (-1625 2600);
DISPLAY INVISIBLE (-1625 2600);
FORCEPROP 2 LAST CDS_SEC 1
J 0
(-1625 2650);
PAINT ORANGE (-1625 2650);
DISPLAY INVISIBLE (-1625 2650);
FORCEPROP 2 LAST SEC_TYPE 0402V
J 0
(-1625 2725);
DISPLAY 1.021277 (-1625 2725);
PAINT ORANGE (-1625 2725);
DISPLAY INVISIBLE (-1625 2725);
FORCEPROP 2 LAST SEC 1
J 0
(-1625 2725);
DISPLAY 0.680851 (-1625 2725);
PAINT MONO (-1625 2725);
DISPLAY INVISIBLE (-1625 2725);
FORCEADD RES..1
(-1125 3050);
FORCEPROP 1 LAST VALUE 1.0
J 2
(-1225 2925);
DISPLAY 0.617021 (-1225 2925);
PAINT SKYBLUE (-1225 2925);
FORCEPROP 1 LAST TOLERANCE 1%
J 0
(-1175 2925);
DISPLAY 0.617021 (-1175 2925);
PAINT SKYBLUE (-1175 2925);
FORCEPROP 1 LASTPIN (-1225 3050) $PN 1
J 0
(-1213 3062);
DISPLAY 0.617021 (-1213 3062);
PAINT ORANGE (-1213 3062);
FORCEPROP 1 LASTPIN (-1025 3050) $PN 2
J 0
(-1063 3062);
DISPLAY 0.617021 (-1063 3062);
PAINT ORANGE (-1063 3062);
FORCEPROP 1 LAST LOCATION R9U1
J 0
(-1175 3100);
DISPLAY 0.617021 (-1175 3100);
PAINT AQUA (-1175 3100);
FORCEPROP 1 LAST MATERIAL CHIP
J 0
(-1050 2875);
DISPLAY 0.617021 (-1050 2875);
PAINT SKYBLUE (-1050 2875);
FORCEPROP 1 LAST WATTAGE 1/16W
J 2
(-1100 2875);
DISPLAY 0.617021 (-1100 2875);
PAINT SKYBLUE (-1100 2875);
FORCEPROP 1 LAST PACK_TYPE 0402
J 0
(-1075 2925);
DISPLAY 0.617021 (-1075 2925);
PAINT SKYBLUE (-1075 2925);
FORCEPROP 1 LAST PART_NUMBER G21796-090
J 0
(-1250 2975);
DISPLAY 0.617021 (-1250 2975);
PAINT BLUE (-1250 2975);
FORCEPROP 2 LAST CDS_LIB mstr_discrete
J 0
(-1125 3050);
PAINT ORANGE (-1125 3050);
DISPLAY INVISIBLE (-1125 3050);
FORCEPROP 2 LAST ROOM VDDQ_GHJ_PWR_VR
J 0
(-1175 3150);
DISPLAY 1.361702 (-1175 3150);
PAINT ORANGE (-1175 3150);
DISPLAY INVISIBLE (-1175 3150);
FORCEPROP 1 LAST PATH I52
J 0
(-1175 3200);
DISPLAY 1.319149 (-1175 3200);
PAINT WHITE (-1175 3200);
DISPLAY INVISIBLE (-1175 3200);
FORCEPROP 2 LAST CDS_LOCATION R9U1
J 0
(-1175 3100);
DISPLAY 0.617021 (-1175 3100);
PAINT AQUA (-1175 3100);
DISPLAY INVISIBLE (-1175 3100);
FORCEPROP 2 LAST SEC 1
J 0
(-1175 3275);
DISPLAY 0.680851 (-1175 3275);
PAINT MONO (-1175 3275);
DISPLAY INVISIBLE (-1175 3275);
FORCEPROP 2 LAST SEC_TYPE 0402
J 0
(-1175 3275);
DISPLAY 1.021277 (-1175 3275);
PAINT ORANGE (-1175 3275);
DISPLAY INVISIBLE (-1175 3275);
FORCEADD CAP_A..1
R 2
(-525 2500);
FORCEPROP 1 LAST VOLTAGE 6.3V
J 2
(-575 2500);
DISPLAY 0.617021 (-575 2500);
PAINT SKYBLUE (-575 2500);
FORCEPROP 1 LAST TOLERANCE 10%
J 2
(-575 2450);
DISPLAY 0.617021 (-575 2450);
PAINT SKYBLUE (-575 2450);
FORCEPROP 1 LAST MATERIAL X6S
J 2
(-575 2400);
DISPLAY 0.617021 (-575 2400);
PAINT SKYBLUE (-575 2400);
FORCEPROP 1 LASTPIN (-525 2400) $PN 2
J 2
(-535 2380);
DISPLAY 0.617021 (-535 2380);
PAINT ORANGE (-535 2380);
FORCEPROP 1 LAST VALUE 1.0UF
J 2
(-575 2550);
DISPLAY 0.617021 (-575 2550);
PAINT SKYBLUE (-575 2550);
FORCEPROP 1 LASTPIN (-525 2600) $PN 1
J 2
(-535 2580);
DISPLAY 0.617021 (-535 2580);
PAINT ORANGE (-535 2580);
FORCEPROP 1 LAST LOCATION C1G4
J 2
(-575 2600);
DISPLAY 0.617021 (-575 2600);
PAINT AQUA (-575 2600);
FORCEPROP 1 LAST PART_NUMBER D97712-004
J 2
(-575 2350);
DISPLAY 0.617021 (-575 2350);
PAINT BLUE (-575 2350);
FORCEPROP 1 LAST PACK_TYPE 0402V
J 2
(-575 2300);
DISPLAY 0.617021 (-575 2300);
PAINT SKYBLUE (-575 2300);
FORCEPROP 2 LAST CDS_LIB dev_discrete
J 0
(-525 2500);
PAINT ORANGE (-525 2500);
DISPLAY INVISIBLE (-525 2500);
FORCEPROP 2 LAST ROOM VDDQ_GHJ_PWR_VR
J 0
(-575 2650);
DISPLAY 1.361702 (-575 2650);
PAINT ORANGE (-575 2650);
DISPLAY INVISIBLE (-575 2650);
FORCEPROP 1 LAST PATH I53
J 2
(-575 2650);
DISPLAY 0.978723 (-575 2650);
PAINT WHITE (-575 2650);
DISPLAY INVISIBLE (-575 2650);
FORCEPROP 2 LAST SEC 1
J 0
(-575 2725);
DISPLAY 0.680851 (-575 2725);
PAINT MONO (-575 2725);
DISPLAY INVISIBLE (-575 2725);
FORCEPROP 2 LAST SEC_TYPE 0402V
J 0
(-575 2725);
DISPLAY 1.021277 (-575 2725);
PAINT ORANGE (-575 2725);
DISPLAY INVISIBLE (-575 2725);
FORCEPROP 2 LAST CDS_SEC 1
J 0
(-575 2650);
PAINT ORANGE (-575 2650);
DISPLAY INVISIBLE (-575 2650);
FORCEPROP 2 LAST CDS_LOCATION C1G4
J 2
(-575 2600);
DISPLAY 0.617021 (-575 2600);
PAINT AQUA (-575 2600);
DISPLAY INVISIBLE (-575 2600);
FORCEADD CAP..1
(-400 2500);
FORCEPROP 1 LASTPIN (-400 2400) $PN 2
J 0
(-390 2380);
DISPLAY 0.617021 (-390 2380);
PAINT ORANGE (-390 2380);
FORCEPROP 1 LAST MATERIAL X7R
J 0
(-350 2400);
DISPLAY 0.617021 (-350 2400);
PAINT SKYBLUE (-350 2400);
FORCEPROP 1 LAST VOLTAGE 16V
J 0
(-350 2500);
DISPLAY 0.617021 (-350 2500);
PAINT SKYBLUE (-350 2500);
FORCEPROP 1 LAST TOLERANCE 10%
J 0
(-350 2450);
DISPLAY 0.617021 (-350 2450);
PAINT SKYBLUE (-350 2450);
FORCEPROP 1 LAST PART_NUMBER A36096-155
J 0
(-350 2350);
DISPLAY 0.617021 (-350 2350);
PAINT BLUE (-350 2350);
FORCEPROP 1 LAST PACK_TYPE 0402
J 0
(-350 2300);
DISPLAY 0.617021 (-350 2300);
PAINT SKYBLUE (-350 2300);
FORCEPROP 1 LAST VALUE 0.22UF
J 0
(-350 2550);
DISPLAY 0.617021 (-350 2550);
PAINT SKYBLUE (-350 2550);
FORCEPROP 1 LASTPIN (-400 2600) $PN 1
J 0
(-390 2580);
DISPLAY 0.617021 (-390 2580);
PAINT ORANGE (-390 2580);
FORCEPROP 1 LAST LOCATION C1G5
J 0
(-350 2600);
DISPLAY 0.617021 (-350 2600);
PAINT AQUA (-350 2600);
FORCEPROP 2 LAST CDS_LIB mstr_discrete
J 0
(-400 2500);
PAINT ORANGE (-400 2500);
DISPLAY INVISIBLE (-400 2500);
FORCEPROP 1 LAST PATH I54
J 0
(-350 2650);
DISPLAY 1.319149 (-350 2650);
PAINT WHITE (-350 2650);
DISPLAY INVISIBLE (-350 2650);
FORCEPROP 2 LAST ROOM VDDQ_GHJ_PWR_VR
J 0
(-350 2650);
DISPLAY 1.361702 (-350 2650);
PAINT ORANGE (-350 2650);
DISPLAY INVISIBLE (-350 2650);
FORCEPROP 2 LAST SEC_TYPE 0402
J 0
(-350 2725);
DISPLAY 1.021277 (-350 2725);
PAINT ORANGE (-350 2725);
DISPLAY INVISIBLE (-350 2725);
FORCEPROP 2 LAST SEC 1
J 0
(-350 2725);
DISPLAY 0.680851 (-350 2725);
PAINT MONO (-350 2725);
DISPLAY INVISIBLE (-350 2725);
FORCEPROP 2 LAST CDS_LOCATION C1G5
J 0
(-350 2600);
DISPLAY 0.617021 (-350 2600);
PAINT AQUA (-350 2600);
DISPLAY INVISIBLE (-350 2600);
FORCEADD INDUCTOR..1
(3100 1950);
FORCEPROP 1 LASTPIN (3200 1950) $PN 2
J 2
(3210 1960);
DISPLAY 0.617021 (3210 1960);
PAINT WHITE (3210 1960);
FORCEPROP 1 LAST PART_NUMBER D92183-034
J 0
(2975 1900);
DISPLAY 0.617021 (2975 1900);
PAINT BLUE (2975 1900);
FORCEPROP 1 LAST VALUE 0.12UH
J 2
(3095 1840);
DISPLAY 0.617021 (3095 1840);
PAINT SKYBLUE (3095 1840);
FORCEPROP 1 LAST PACK_TYPE SM
J 0
(3265 1840);
DISPLAY 0.617021 (3265 1840);
PAINT SKYBLUE (3265 1840);
FORCEPROP 1 LASTPIN (3000 1950) $PN 1
J 0
(3000 1960);
DISPLAY 0.617021 (3000 1960);
PAINT WHITE (3000 1960);
FORCEPROP 1 LAST LOCATION L1G1
J 0
(3000 2000);
DISPLAY 0.617021 (3000 2000);
PAINT AQUA (3000 2000);
FORCEPROP 1 LAST MATERIAL IND
J 0
(3140 1840);
DISPLAY 0.617021 (3140 1840);
PAINT SKYBLUE (3140 1840);
FORCEPROP 2 LAST CDS_LOCATION L1G1
J 0
(3000 2000);
DISPLAY 0.617021 (3000 2000);
PAINT AQUA (3000 2000);
DISPLAY INVISIBLE (3000 2000);
FORCEPROP 2 LAST CDS_LIB mstr_discrete
J 0
(3100 1950);
PAINT ORANGE (3100 1950);
DISPLAY INVISIBLE (3100 1950);
FORCEPROP 2 LAST ROOM VDDQ_GHJ_PWR_VR
J 0
(3000 2050);
DISPLAY 1.361702 (3000 2050);
PAINT ORANGE (3000 2050);
DISPLAY INVISIBLE (3000 2050);
FORCEPROP 1 LAST PATH I55
J 0
(3000 2100);
DISPLAY 1.319149 (3000 2100);
PAINT ORANGE (3000 2100);
DISPLAY INVISIBLE (3000 2100);
FORCEPROP 2 LAST SEC 1
J 0
(3000 2175);
DISPLAY 0.680851 (3000 2175);
PAINT MONO (3000 2175);
DISPLAY INVISIBLE (3000 2175);
FORCEPROP 2 LAST SEC_TYPE SM
J 0
(3000 2175);
DISPLAY 1.021277 (3000 2175);
PAINT ORANGE (3000 2175);
DISPLAY INVISIBLE (3000 2175);
FORCEADD OFFPAGE..2
(3100 2475);
FORCEPROP 2 LAST $XR1 223 
J 0
(3409 2475);
DISPLAY 0.638298 (3409 2475);
PAINT MONO (3409 2475);
FORCEPROP 2 LAST $XR0 224 
J 0
(3289 2475);
DISPLAY 0.638298 (3289 2475);
PAINT MONO (3289 2475);
FORCEPROP 1 LAST OFFPAGE TRUE
J 0
(3425 2350);
DISPLAY 1.723404 (3425 2350);
PAINT GREEN (3425 2350);
DISPLAY INVISIBLE (3425 2350);
FORCEPROP 2 LAST BOM_COST VDDQ_GHJ_PWR_VR
J 0
(3300 2525);
DISPLAY 1.446809 (3300 2525);
PAINT MONO (3300 2525);
DISPLAY INVISIBLE (3300 2525);
FORCEPROP 2 LAST PATH I58
J 0
(3280 2550);
DISPLAY 1.361702 (3280 2550);
PAINT ORANGE (3280 2550);
DISPLAY INVISIBLE (3280 2550);
FORCEPROP 2 LAST CDS_LIB mstr_standard
J 0
(3100 2475);
PAINT ORANGE (3100 2475);
DISPLAY INVISIBLE (3100 2475);
FORCEPROP 2 LAST ROOM VDDQ_GHJ_PWR_VR
J 0
(2700 2550);
DISPLAY 1.936170 (2700 2550);
PAINT ORANGE (2700 2550);
DISPLAY INVISIBLE (2700 2550);
FORCEPROP 1 LAST COMMENT_BODY TRUE
J 0
(3055 2380);
DISPLAY 1.723404 (3055 2380);
PAINT GREEN (3055 2380);
DISPLAY INVISIBLE (3055 2380);
FORCEADD CAP..1
(4000 1750);
FORCEPROP 1 LASTPIN (4000 1650) $PN 2
J 0
(4010 1630);
DISPLAY 0.617021 (4010 1630);
PAINT GREEN (4010 1630);
FORCEPROP 1 LASTPIN (4000 1850) $PN 1
J 0
(4010 1830);
DISPLAY 0.617021 (4010 1830);
PAINT GREEN (4010 1830);
FORCEPROP 1 LAST MATERIAL X6S
J 0
(4050 1650);
DISPLAY 0.617021 (4050 1650);
PAINT SKYBLUE (4050 1650);
FORCEPROP 1 LAST PACK_TYPE 0805LF
J 0
(4050 1550);
DISPLAY 0.617021 (4050 1550);
PAINT SKYBLUE (4050 1550);
FORCEPROP 1 LAST TOLERANCE 20%
J 0
(4050 1700);
DISPLAY 0.617021 (4050 1700);
PAINT SKYBLUE (4050 1700);
FORCEPROP 1 LAST VALUE 22UF
J 0
(4050 1800);
DISPLAY 0.617021 (4050 1800);
PAINT SKYBLUE (4050 1800);
FORCEPROP 1 LAST PART_NUMBER C95333-002
J 0
(4050 1600);
DISPLAY 0.617021 (4050 1600);
PAINT BLUE (4050 1600);
FORCEPROP 1 LAST LOCATION C1G17
J 0
(4050 1850);
DISPLAY 0.617021 (4050 1850);
PAINT AQUA (4050 1850);
FORCEPROP 2 LAST CDS_LIB mstr_discrete
J 0
(4000 1750);
DISPLAY 1.936170 (4000 1750);
PAINT ORANGE (4000 1750);
DISPLAY INVISIBLE (4000 1750);
FORCEPROP 1 LAST VOLTAGE 4V
J 0
(4050 1750);
DISPLAY 1.446809 (4050 1750);
PAINT SKYBLUE (4050 1750);
DISPLAY INVISIBLE (4050 1750);
FORCEPROP 2 LAST CDS_LOCATION C1G17
J 0
(4050 1850);
DISPLAY 0.617021 (4050 1850);
PAINT AQUA (4050 1850);
DISPLAY INVISIBLE (4050 1850);
FORCEPROP 2 LAST ROOM VDDQ_GHJ_PWR_VR
J 0
(4050 1900);
DISPLAY 1.446809 (4050 1900);
PAINT MONO (4050 1900);
DISPLAY INVISIBLE (4050 1900);
FORCEPROP 1 LAST PATH I6
J 0
(4050 1900);
DISPLAY 0.978723 (4050 1900);
PAINT WHITE (4050 1900);
DISPLAY INVISIBLE (4050 1900);
FORCEPROP 2 LAST BOM_COST VDDQ_GHJ_PWR_VR
J 0
(4050 1900);
DISPLAY 1.446809 (4050 1900);
PAINT MONO (4050 1900);
DISPLAY INVISIBLE (4050 1900);
FORCEPROP 2 LAST SEC 1
J 0
(4055 1950);
DISPLAY 0.680851 (4055 1950);
PAINT MONO (4055 1950);
DISPLAY INVISIBLE (4055 1950);
FORCEPROP 2 LAST SEC_TYPE 0805LF
J 0
(4055 1950);
DISPLAY 1.021277 (4055 1950);
PAINT ORANGE (4055 1950);
DISPLAY INVISIBLE (4055 1950);
FORCEADD OFFPAGE..2
(3625 775);
FORCEPROP 2 LAST $XR0 223 
J 0
(3814 775);
DISPLAY 0.638298 (3814 775);
PAINT MONO (3814 775);
FORCEPROP 1 LAST COMMENT_BODY TRUE
J 0
(3580 680);
DISPLAY 1.723404 (3580 680);
PAINT GREEN (3580 680);
DISPLAY INVISIBLE (3580 680);
FORCEPROP 2 LAST ROOM VDDQ_GHJ_PWR_VR
J 0
(3225 850);
DISPLAY 1.936170 (3225 850);
PAINT ORANGE (3225 850);
DISPLAY INVISIBLE (3225 850);
FORCEPROP 2 LAST PATH I61
J 0
(3805 850);
DISPLAY 1.361702 (3805 850);
PAINT ORANGE (3805 850);
DISPLAY INVISIBLE (3805 850);
FORCEPROP 2 LAST BOM_COST VDDQ_GHJ_PWR_VR
J 0
(3825 825);
DISPLAY 1.446809 (3825 825);
PAINT MONO (3825 825);
DISPLAY INVISIBLE (3825 825);
FORCEPROP 2 LAST CDS_LIB mstr_standard
J 0
(3625 775);
PAINT ORANGE (3625 775);
DISPLAY INVISIBLE (3625 775);
FORCEPROP 1 LAST OFFPAGE TRUE
J 0
(3950 650);
DISPLAY 1.723404 (3950 650);
PAINT GREEN (3950 650);
DISPLAY INVISIBLE (3950 650);
FORCEADD OFFPAGE..2
(3650 425);
FORCEPROP 2 LAST $XR0 223 
J 0
(3839 425);
DISPLAY 0.638298 (3839 425);
PAINT MONO (3839 425);
FORCEPROP 2 LAST ROOM VDDQ_GHJ_PWR_VR
J 0
(3250 500);
DISPLAY 1.936170 (3250 500);
PAINT ORANGE (3250 500);
DISPLAY INVISIBLE (3250 500);
FORCEPROP 1 LAST COMMENT_BODY TRUE
J 0
(3605 330);
DISPLAY 1.723404 (3605 330);
PAINT GREEN (3605 330);
DISPLAY INVISIBLE (3605 330);
FORCEPROP 2 LAST CDS_LIB mstr_standard
J 0
(3650 425);
PAINT ORANGE (3650 425);
DISPLAY INVISIBLE (3650 425);
FORCEPROP 1 LAST OFFPAGE TRUE
J 0
(3975 300);
DISPLAY 1.723404 (3975 300);
PAINT GREEN (3975 300);
DISPLAY INVISIBLE (3975 300);
FORCEPROP 2 LAST PATH I62
J 0
(3830 500);
DISPLAY 1.361702 (3830 500);
PAINT ORANGE (3830 500);
DISPLAY INVISIBLE (3830 500);
FORCEPROP 2 LAST BOM_COST VDDQ_GHJ_PWR_VR
J 0
(3850 475);
DISPLAY 1.446809 (3850 475);
PAINT MONO (3850 475);
DISPLAY INVISIBLE (3850 475);
FORCEADD OFFPAGE..2
(3475 100);
FORCEPROP 2 LAST $XR1 223 
J 0
(3784 100);
DISPLAY 0.638298 (3784 100);
PAINT MONO (3784 100);
FORCEPROP 2 LAST $XR0 224 
J 0
(3664 100);
DISPLAY 0.638298 (3664 100);
PAINT MONO (3664 100);
FORCEPROP 2 LAST ROOM VDDQ_GHJ_PWR_VR
J 0
(3075 175);
DISPLAY 1.936170 (3075 175);
PAINT ORANGE (3075 175);
DISPLAY INVISIBLE (3075 175);
FORCEPROP 2 LAST BOM_COST VDDQ_GHJ_PWR_VR
J 0
(3675 150);
DISPLAY 1.446809 (3675 150);
PAINT MONO (3675 150);
DISPLAY INVISIBLE (3675 150);
FORCEPROP 2 LAST PATH I63
J 0
(3655 175);
DISPLAY 1.361702 (3655 175);
PAINT ORANGE (3655 175);
DISPLAY INVISIBLE (3655 175);
FORCEPROP 1 LAST OFFPAGE TRUE
J 0
(3800 -25);
DISPLAY 1.723404 (3800 -25);
PAINT GREEN (3800 -25);
DISPLAY INVISIBLE (3800 -25);
FORCEPROP 2 LAST CDS_LIB mstr_standard
J 0
(3475 100);
PAINT ORANGE (3475 100);
DISPLAY INVISIBLE (3475 100);
FORCEPROP 1 LAST COMMENT_BODY TRUE
J 0
(3430 5);
DISPLAY 1.723404 (3430 5);
PAINT GREEN (3430 5);
DISPLAY INVISIBLE (3430 5);
FORCEADD PVDDQ_GHJ..1
(4000 -325);
FORCEPROP 3 LASTPIN (4000 -375) SIG_NAME PVDDQ_GHJ\g
J 0
(4010 -365);
DISPLAY 0.659574 (4010 -365);
PAINT MONO (4010 -365);
DISPLAY INVISIBLE (4010 -365);
FORCEPROP 1 LAST VOLTAGE 1.2V
J 0
(3955 -368);
DISPLAY 0.340426 (3955 -368);
PAINT SKYBLUE (3955 -368);
DISPLAY INVISIBLE (3955 -368);
FORCEPROP 1 LAST BODY_TYPE PLUMBING
J 0
(3955 -368);
DISPLAY 0.340426 (3955 -368);
PAINT GREEN (3955 -368);
DISPLAY INVISIBLE (3955 -368);
FORCEPROP 1 LAST PATH I64
J 0
(4050 -300);
DISPLAY 0.872340 (4050 -300);
PAINT AQUA (4050 -300);
DISPLAY INVISIBLE (4050 -300);
FORCEPROP 2 LAST CDS_LIB mstr_symbols
J 0
(4000 -325);
PAINT ORANGE (4000 -325);
DISPLAY INVISIBLE (4000 -325);
FORCEPROP 1 LAST HDL_POWER PVDDQ_GHJ
J 1
(4000 -275);
DISPLAY 0.872340 (4000 -275);
PAINT GREEN (4000 -275);
DISPLAY INVISIBLE (4000 -275);
FORCEADD INDUCTOR..1
(3100 -425);
FORCEPROP 1 LAST LOCATION L1F2
J 0
(3000 -375);
DISPLAY 0.617021 (3000 -375);
PAINT AQUA (3000 -375);
FORCEPROP 1 LAST VALUE 0.12UH
J 2
(3095 -535);
DISPLAY 0.617021 (3095 -535);
PAINT SKYBLUE (3095 -535);
FORCEPROP 1 LAST PART_NUMBER D92183-034
J 0
(2975 -475);
DISPLAY 0.617021 (2975 -475);
PAINT BLUE (2975 -475);
FORCEPROP 1 LASTPIN (3000 -425) $PN 1
J 0
(3000 -415);
DISPLAY 0.617021 (3000 -415);
PAINT WHITE (3000 -415);
FORCEPROP 1 LASTPIN (3200 -425) $PN 2
J 2
(3210 -415);
DISPLAY 0.617021 (3210 -415);
PAINT WHITE (3210 -415);
FORCEPROP 1 LAST MATERIAL IND
J 0
(3140 -535);
DISPLAY 0.617021 (3140 -535);
PAINT SKYBLUE (3140 -535);
FORCEPROP 1 LAST PACK_TYPE SM
J 0
(3265 -535);
DISPLAY 0.617021 (3265 -535);
PAINT SKYBLUE (3265 -535);
FORCEPROP 2 LAST ROOM VDDQ_GHJ_PWR_VR
J 0
(3000 -325);
DISPLAY 1.361702 (3000 -325);
PAINT ORANGE (3000 -325);
DISPLAY INVISIBLE (3000 -325);
FORCEPROP 1 LAST PATH I65
J 0
(3000 -275);
DISPLAY 1.319149 (3000 -275);
PAINT ORANGE (3000 -275);
DISPLAY INVISIBLE (3000 -275);
FORCEPROP 2 LAST CDS_LOCATION L1F2
J 0
(3000 -375);
DISPLAY 0.617021 (3000 -375);
PAINT AQUA (3000 -375);
DISPLAY INVISIBLE (3000 -375);
FORCEPROP 2 LAST SEC 1
J 0
(3000 -200);
DISPLAY 0.680851 (3000 -200);
PAINT MONO (3000 -200);
DISPLAY INVISIBLE (3000 -200);
FORCEPROP 2 LAST SEC_TYPE SM
J 0
(3000 -200);
DISPLAY 1.021277 (3000 -200);
PAINT ORANGE (3000 -200);
DISPLAY INVISIBLE (3000 -200);
FORCEPROP 2 LAST CDS_LIB mstr_discrete
J 0
(3100 -425);
PAINT ORANGE (3100 -425);
DISPLAY INVISIBLE (3100 -425);
FORCEADD CAP..1
(4000 -625);
FORCEPROP 1 LASTPIN (4000 -525) $PN 1
J 0
(4010 -545);
DISPLAY 0.617021 (4010 -545);
PAINT ORANGE (4010 -545);
FORCEPROP 1 LASTPIN (4000 -725) $PN 2
J 0
(4010 -745);
DISPLAY 0.617021 (4010 -745);
PAINT ORANGE (4010 -745);
FORCEPROP 1 LAST MATERIAL X6S
J 0
(4050 -725);
DISPLAY 0.617021 (4050 -725);
PAINT SKYBLUE (4050 -725);
FORCEPROP 1 LAST PACK_TYPE 0805LF
J 0
(4050 -825);
DISPLAY 0.617021 (4050 -825);
PAINT SKYBLUE (4050 -825);
FORCEPROP 1 LAST TOLERANCE 20%
J 0
(4050 -675);
DISPLAY 0.617021 (4050 -675);
PAINT SKYBLUE (4050 -675);
FORCEPROP 1 LAST VALUE 22UF
J 0
(4050 -575);
DISPLAY 0.617021 (4050 -575);
PAINT SKYBLUE (4050 -575);
FORCEPROP 1 LAST PART_NUMBER C95333-002
J 0
(4050 -775);
DISPLAY 0.617021 (4050 -775);
PAINT BLUE (4050 -775);
FORCEPROP 1 LAST LOCATION C1G20
J 0
(4050 -525);
DISPLAY 0.617021 (4050 -525);
PAINT AQUA (4050 -525);
FORCEPROP 2 LAST CDS_LIB mstr_discrete
J 0
(4000 -625);
PAINT ORANGE (4000 -625);
DISPLAY INVISIBLE (4000 -625);
FORCEPROP 1 LAST VOLTAGE 4V
J 0
(4050 -625);
DISPLAY 1.446809 (4050 -625);
PAINT SKYBLUE (4050 -625);
DISPLAY INVISIBLE (4050 -625);
FORCEPROP 2 LAST CDS_LOCATION C1G20
J 0
(4050 -525);
DISPLAY 0.617021 (4050 -525);
PAINT AQUA (4050 -525);
DISPLAY INVISIBLE (4050 -525);
FORCEPROP 2 LAST ROOM VDDQ_GHJ_PWR_VR
J 0
(4050 -475);
DISPLAY 1.446809 (4050 -475);
PAINT MONO (4050 -475);
DISPLAY INVISIBLE (4050 -475);
FORCEPROP 1 LAST PATH I68
J 0
(4050 -475);
DISPLAY 1.319149 (4050 -475);
PAINT WHITE (4050 -475);
DISPLAY INVISIBLE (4050 -475);
FORCEPROP 2 LAST BOM_COST VDDQ_GHJ_PWR_VR
J 0
(4050 -475);
DISPLAY 1.446809 (4050 -475);
PAINT MONO (4050 -475);
DISPLAY INVISIBLE (4050 -475);
FORCEPROP 2 LAST SEC 1
J 0
(4055 -400);
DISPLAY 0.680851 (4055 -400);
PAINT MONO (4055 -400);
DISPLAY INVISIBLE (4055 -400);
FORCEPROP 2 LAST SEC_TYPE 0805LF
J 0
(4055 -400);
DISPLAY 1.021277 (4055 -400);
PAINT ORANGE (4055 -400);
DISPLAY INVISIBLE (4055 -400);
FORCEADD GND..1
(4000 -850);
FORCEPROP 3 LASTPIN (4000 -800) SIG_NAME GND\g
J 0
(4010 -790);
DISPLAY 0.659574 (4010 -790);
PAINT MONO (4010 -790);
DISPLAY INVISIBLE (4010 -790);
FORCEPROP 2 LAST ROOM VDDQ_GHJ_PWR_VR
J 0
(3450 -775);
DISPLAY 1.936170 (3450 -775);
PAINT ORANGE (3450 -775);
DISPLAY INVISIBLE (3450 -775);
FORCEPROP 2 LAST BOM_COST VDDQ_GHJ_PWR_VR
J 0
(3625 -775);
DISPLAY 1.446809 (3625 -775);
PAINT MONO (3625 -775);
DISPLAY INVISIBLE (3625 -775);
FORCEPROP 1 LAST PATH I69
J 0
(4075 -850);
DISPLAY 1.170213 (4075 -850);
PAINT AQUA (4075 -850);
DISPLAY INVISIBLE (4075 -850);
FORCEPROP 1 LAST BODY_TYPE PLUMBING
J 0
(3955 -893);
DISPLAY 0.340426 (3955 -893);
PAINT GREEN (3955 -893);
DISPLAY INVISIBLE (3955 -893);
FORCEPROP 1 LAST SIZE 1B
J 0
(4075 -900);
DISPLAY 1.723404 (4075 -900);
PAINT GREEN (4075 -900);
DISPLAY INVISIBLE (4075 -900);
FORCEPROP 1 LAST VOLTAGE 0
J 0
(4000 -850);
PAINT SKYBLUE (4000 -850);
DISPLAY INVISIBLE (4000 -850);
FORCEPROP 2 LAST CDS_LIB mstr_symbols
J 0
(4000 -850);
PAINT ORANGE (4000 -850);
DISPLAY INVISIBLE (4000 -850);
FORCEPROP 1 LAST HDL_POWER GND
J 0
(4000 -700);
DISPLAY 1.723404 (4000 -700);
PAINT GREEN (4000 -700);
DISPLAY INVISIBLE (4000 -700);
FORCEADD GND..1
(4000 1525);
FORCEPROP 3 LASTPIN (4000 1575) SIG_NAME GND\g
J 0
(4010 1585);
DISPLAY 0.659574 (4010 1585);
PAINT MONO (4010 1585);
DISPLAY INVISIBLE (4010 1585);
FORCEPROP 2 LAST ROOM VDDQ_GHJ_PWR_VR
J 0
(3450 1600);
DISPLAY 1.936170 (3450 1600);
PAINT ORANGE (3450 1600);
DISPLAY INVISIBLE (3450 1600);
FORCEPROP 1 LAST BODY_TYPE PLUMBING
J 0
(3955 1482);
DISPLAY 0.340426 (3955 1482);
PAINT GREEN (3955 1482);
DISPLAY INVISIBLE (3955 1482);
FORCEPROP 1 LAST PATH I7
J 0
(4075 1525);
DISPLAY 0.893617 (4075 1525);
PAINT AQUA (4075 1525);
DISPLAY INVISIBLE (4075 1525);
FORCEPROP 1 LAST SIZE 1B
J 0
(4075 1475);
DISPLAY 1.723404 (4075 1475);
PAINT GREEN (4075 1475);
DISPLAY INVISIBLE (4075 1475);
FORCEPROP 2 LAST CDS_LIB mstr_symbols
J 0
(4000 1525);
DISPLAY 1.936170 (4000 1525);
PAINT ORANGE (4000 1525);
DISPLAY INVISIBLE (4000 1525);
FORCEPROP 1 LAST VOLTAGE 0
J 0
(4000 1525);
PAINT SKYBLUE (4000 1525);
DISPLAY INVISIBLE (4000 1525);
FORCEPROP 2 LAST BOM_COST VDDQ_GHJ_PWR_VR
J 0
(3625 1600);
DISPLAY 1.446809 (3625 1600);
PAINT MONO (3625 1600);
DISPLAY INVISIBLE (3625 1600);
FORCEPROP 1 LAST HDL_POWER GND
J 0
(4000 1675);
DISPLAY 1.723404 (4000 1675);
PAINT GREEN (4000 1675);
DISPLAY INVISIBLE (4000 1675);
FORCEADD GND..1
(2325 -875);
FORCEPROP 3 LASTPIN (2325 -825) SIG_NAME GND\g
J 0
(2335 -815);
DISPLAY 0.659574 (2335 -815);
PAINT MONO (2335 -815);
DISPLAY INVISIBLE (2335 -815);
FORCEPROP 2 LAST ROOM VDDQ_GHJ_PWR_VR
J 0
(1775 -800);
DISPLAY 1.936170 (1775 -800);
PAINT ORANGE (1775 -800);
DISPLAY INVISIBLE (1775 -800);
FORCEPROP 2 LAST BOM_COST VDDQ_GHJ_PWR_VR
J 0
(1950 -800);
DISPLAY 1.446809 (1950 -800);
PAINT MONO (1950 -800);
DISPLAY INVISIBLE (1950 -800);
FORCEPROP 1 LAST BODY_TYPE PLUMBING
J 0
(2280 -918);
DISPLAY 0.340426 (2280 -918);
PAINT GREEN (2280 -918);
DISPLAY INVISIBLE (2280 -918);
FORCEPROP 1 LAST VOLTAGE 0
J 0
(2325 -875);
PAINT SKYBLUE (2325 -875);
DISPLAY INVISIBLE (2325 -875);
FORCEPROP 1 LAST SIZE 1B
J 0
(2400 -925);
DISPLAY 1.723404 (2400 -925);
PAINT GREEN (2400 -925);
DISPLAY INVISIBLE (2400 -925);
FORCEPROP 2 LAST CDS_LIB mstr_symbols
J 0
(2325 -875);
PAINT ORANGE (2325 -875);
DISPLAY INVISIBLE (2325 -875);
FORCEPROP 1 LAST PATH I70
J 0
(2400 -875);
DISPLAY 1.170213 (2400 -875);
PAINT AQUA (2400 -875);
DISPLAY INVISIBLE (2400 -875);
FORCEPROP 1 LAST HDL_POWER GND
J 0
(2325 -725);
DISPLAY 1.723404 (2325 -725);
PAINT GREEN (2325 -725);
DISPLAY INVISIBLE (2325 -725);
FORCEADD CAP..1
(-475 150);
FORCEPROP 1 LAST PACK_TYPE 0402
J 0
(-425 -50);
DISPLAY 0.617021 (-425 -50);
PAINT SKYBLUE (-425 -50);
FORCEPROP 1 LAST PART_NUMBER A36096-155
J 0
(-425 0);
DISPLAY 0.617021 (-425 0);
PAINT BLUE (-425 0);
FORCEPROP 1 LASTPIN (-475 250) $PN 1
J 0
(-465 230);
DISPLAY 0.617021 (-465 230);
PAINT ORANGE (-465 230);
FORCEPROP 1 LAST TOLERANCE 10%
J 0
(-425 100);
DISPLAY 0.617021 (-425 100);
PAINT SKYBLUE (-425 100);
FORCEPROP 1 LASTPIN (-475 50) $PN 2
J 0
(-465 30);
DISPLAY 0.617021 (-465 30);
PAINT ORANGE (-465 30);
FORCEPROP 1 LAST MATERIAL X7R
J 0
(-425 50);
DISPLAY 0.617021 (-425 50);
PAINT SKYBLUE (-425 50);
FORCEPROP 1 LAST VOLTAGE 16V
J 0
(-425 150);
DISPLAY 0.617021 (-425 150);
PAINT SKYBLUE (-425 150);
FORCEPROP 1 LAST LOCATION C1G29
J 0
(-425 250);
DISPLAY 0.617021 (-425 250);
PAINT AQUA (-425 250);
FORCEPROP 1 LAST VALUE 0.22UF
J 0
(-425 200);
DISPLAY 0.617021 (-425 200);
PAINT SKYBLUE (-425 200);
FORCEPROP 2 LAST CDS_LIB mstr_discrete
J 0
(-475 150);
PAINT ORANGE (-475 150);
DISPLAY INVISIBLE (-475 150);
FORCEPROP 1 LAST PATH I72
J 0
(-425 300);
DISPLAY 1.319149 (-425 300);
PAINT WHITE (-425 300);
DISPLAY INVISIBLE (-425 300);
FORCEPROP 2 LAST SEC_TYPE 0402
J 0
(-425 375);
DISPLAY 1.021277 (-425 375);
PAINT ORANGE (-425 375);
DISPLAY INVISIBLE (-425 375);
FORCEPROP 2 LAST SEC 1
J 0
(-425 375);
DISPLAY 0.680851 (-425 375);
PAINT MONO (-425 375);
DISPLAY INVISIBLE (-425 375);
FORCEPROP 2 LAST ROOM VDDQ_GHJ_PWR_VR
J 0
(-425 300);
DISPLAY 1.361702 (-425 300);
PAINT ORANGE (-425 300);
DISPLAY INVISIBLE (-425 300);
FORCEADD CAP_A..1
R 2
(-575 150);
FORCEPROP 1 LAST PART_NUMBER D97712-004
J 2
(-625 0);
DISPLAY 0.617021 (-625 0);
PAINT BLUE (-625 0);
FORCEPROP 1 LAST PACK_TYPE 0402V
J 2
(-625 -50);
DISPLAY 0.617021 (-625 -50);
PAINT SKYBLUE (-625 -50);
FORCEPROP 1 LAST VALUE 1.0UF
J 2
(-625 200);
DISPLAY 0.617021 (-625 200);
PAINT SKYBLUE (-625 200);
FORCEPROP 1 LAST LOCATION C1F21
J 2
(-625 250);
DISPLAY 0.617021 (-625 250);
PAINT AQUA (-625 250);
FORCEPROP 1 LASTPIN (-575 50) $PN 2
J 2
(-585 30);
DISPLAY 0.617021 (-585 30);
PAINT ORANGE (-585 30);
FORCEPROP 1 LASTPIN (-575 250) $PN 1
J 2
(-585 230);
DISPLAY 0.617021 (-585 230);
PAINT ORANGE (-585 230);
FORCEPROP 1 LAST MATERIAL X6S
J 2
(-625 50);
DISPLAY 0.617021 (-625 50);
PAINT SKYBLUE (-625 50);
FORCEPROP 1 LAST TOLERANCE 10%
J 2
(-625 100);
DISPLAY 0.617021 (-625 100);
PAINT SKYBLUE (-625 100);
FORCEPROP 1 LAST VOLTAGE 6.3V
J 2
(-625 150);
DISPLAY 0.617021 (-625 150);
PAINT SKYBLUE (-625 150);
FORCEPROP 2 LAST CDS_LIB dev_discrete
J 0
(-575 150);
PAINT ORANGE (-575 150);
DISPLAY INVISIBLE (-575 150);
FORCEPROP 2 LAST CDS_LOCATION C1F21
J 2
(-625 250);
DISPLAY 0.617021 (-625 250);
PAINT AQUA (-625 250);
DISPLAY INVISIBLE (-625 250);
FORCEPROP 2 LAST CDS_SEC 1
J 0
(-625 300);
PAINT ORANGE (-625 300);
DISPLAY INVISIBLE (-625 300);
FORCEPROP 2 LAST SEC_TYPE 0402V
J 0
(-625 375);
DISPLAY 1.021277 (-625 375);
PAINT ORANGE (-625 375);
DISPLAY INVISIBLE (-625 375);
FORCEPROP 2 LAST SEC 1
J 0
(-625 375);
DISPLAY 0.680851 (-625 375);
PAINT MONO (-625 375);
DISPLAY INVISIBLE (-625 375);
FORCEPROP 1 LAST PATH I73
J 2
(-625 300);
DISPLAY 0.978723 (-625 300);
PAINT WHITE (-625 300);
DISPLAY INVISIBLE (-625 300);
FORCEPROP 2 LAST ROOM VDDQ_GHJ_PWR_VR
J 0
(-625 300);
DISPLAY 1.361702 (-625 300);
PAINT ORANGE (-625 300);
DISPLAY INVISIBLE (-625 300);
FORCEADD CAP..1
R 2
(-975 -475);
FORCEPROP 1 LASTPIN (-975 -375) $PN 1
J 2
(-985 -395);
DISPLAY 0.617021 (-985 -395);
PAINT ORANGE (-985 -395);
FORCEPROP 1 LAST VALUE 0.220UF
J 2
(-1025 -425);
DISPLAY 0.617021 (-1025 -425);
PAINT SKYBLUE (-1025 -425);
FORCEPROP 1 LAST VOLTAGE 16V
J 2
(-1025 -475);
DISPLAY 0.617021 (-1025 -475);
PAINT SKYBLUE (-1025 -475);
FORCEPROP 1 LAST LOCATION C1F26
J 2
(-1025 -375);
DISPLAY 0.617021 (-1025 -375);
PAINT AQUA (-1025 -375);
FORCEPROP 1 LAST MATERIAL X7R
J 2
(-1025 -575);
DISPLAY 0.617021 (-1025 -575);
PAINT SKYBLUE (-1025 -575);
FORCEPROP 1 LAST TOLERANCE 10%
J 2
(-1025 -525);
DISPLAY 0.617021 (-1025 -525);
PAINT SKYBLUE (-1025 -525);
FORCEPROP 1 LAST PACK_TYPE 0402
J 2
(-1025 -675);
DISPLAY 0.617021 (-1025 -675);
PAINT SKYBLUE (-1025 -675);
FORCEPROP 1 LASTPIN (-975 -575) $PN 2
J 2
(-985 -595);
DISPLAY 0.617021 (-985 -595);
PAINT ORANGE (-985 -595);
FORCEPROP 1 LAST PART_NUMBER A36096-104
J 2
(-1025 -625);
DISPLAY 0.617021 (-1025 -625);
PAINT BLUE (-1025 -625);
FORCEPROP 2 LAST ROOM VDDQ_GHJ_PWR_VR
J 0
(-1025 -325);
DISPLAY 1.361702 (-1025 -325);
PAINT ORANGE (-1025 -325);
DISPLAY INVISIBLE (-1025 -325);
FORCEPROP 1 LAST PATH I75
J 2
(-1025 -325);
DISPLAY 0.978723 (-1025 -325);
PAINT WHITE (-1025 -325);
DISPLAY INVISIBLE (-1025 -325);
FORCEPROP 2 LAST CDS_LOCATION C1F26
J 2
(-1025 -375);
DISPLAY 0.617021 (-1025 -375);
PAINT AQUA (-1025 -375);
DISPLAY INVISIBLE (-1025 -375);
FORCEPROP 2 LAST SEC 1
J 0
(-1025 -275);
DISPLAY 0.680851 (-1025 -275);
PAINT MONO (-1025 -275);
DISPLAY INVISIBLE (-1025 -275);
FORCEPROP 2 LAST SEC_TYPE 0402
J 0
(-1025 -275);
DISPLAY 1.021277 (-1025 -275);
PAINT ORANGE (-1025 -275);
DISPLAY INVISIBLE (-1025 -275);
FORCEPROP 0 LAST SPOF TRUE
J 0
(-1025 -275);
DISPLAY 1.021277 (-1025 -275);
PAINT ORANGE (-1025 -275);
DISPLAY INVISIBLE (-1025 -275);
FORCEPROP 2 LAST CDS_LIB mstr_discrete
J 0
(-975 -475);
PAINT ORANGE (-975 -475);
DISPLAY INVISIBLE (-975 -475);
FORCEADD RES..1
(-1175 675);
FORCEPROP 1 LAST WATTAGE 1/16W
J 2
(-1150 500);
DISPLAY 0.617021 (-1150 500);
PAINT SKYBLUE (-1150 500);
FORCEPROP 1 LAST VALUE 1.0
J 2
(-1275 550);
DISPLAY 0.617021 (-1275 550);
PAINT SKYBLUE (-1275 550);
FORCEPROP 1 LASTPIN (-1275 675) $PN 1
J 0
(-1263 687);
DISPLAY 0.617021 (-1263 687);
PAINT ORANGE (-1263 687);
FORCEPROP 1 LAST TOLERANCE 1%
J 0
(-1225 550);
DISPLAY 0.617021 (-1225 550);
PAINT SKYBLUE (-1225 550);
FORCEPROP 1 LAST LOCATION R9U12
J 0
(-1225 725);
DISPLAY 0.617021 (-1225 725);
PAINT AQUA (-1225 725);
FORCEPROP 1 LASTPIN (-1075 675) $PN 2
J 0
(-1113 687);
DISPLAY 0.617021 (-1113 687);
PAINT ORANGE (-1113 687);
FORCEPROP 1 LAST MATERIAL CHIP
J 0
(-1100 500);
DISPLAY 0.617021 (-1100 500);
PAINT SKYBLUE (-1100 500);
FORCEPROP 1 LAST PACK_TYPE 0402
J 0
(-1125 550);
DISPLAY 0.617021 (-1125 550);
PAINT SKYBLUE (-1125 550);
FORCEPROP 1 LAST PART_NUMBER G21796-090
J 0
(-1300 600);
DISPLAY 0.617021 (-1300 600);
PAINT BLUE (-1300 600);
FORCEPROP 2 LAST CDS_LIB mstr_discrete
J 0
(-1175 675);
PAINT ORANGE (-1175 675);
DISPLAY INVISIBLE (-1175 675);
FORCEPROP 2 LAST ROOM VDDQ_GHJ_PWR_VR
J 0
(-1225 775);
DISPLAY 1.361702 (-1225 775);
PAINT ORANGE (-1225 775);
DISPLAY INVISIBLE (-1225 775);
FORCEPROP 1 LAST PATH I76
J 0
(-1225 825);
DISPLAY 1.319149 (-1225 825);
PAINT WHITE (-1225 825);
DISPLAY INVISIBLE (-1225 825);
FORCEPROP 2 LAST SEC 1
J 0
(-1225 900);
DISPLAY 0.680851 (-1225 900);
PAINT MONO (-1225 900);
DISPLAY INVISIBLE (-1225 900);
FORCEPROP 2 LAST SEC_TYPE 0402
J 0
(-1225 900);
DISPLAY 1.021277 (-1225 900);
PAINT ORANGE (-1225 900);
DISPLAY INVISIBLE (-1225 900);
FORCEADD CAP..1
(-1425 75);
FORCEPROP 1 LASTPIN (-1425 -25) $PN 2
J 0
(-1415 -45);
DISPLAY 0.617021 (-1415 -45);
PAINT ORANGE (-1415 -45);
FORCEPROP 1 LAST PACK_TYPE 0402
J 0
(-1375 -125);
DISPLAY 0.617021 (-1375 -125);
PAINT SKYBLUE (-1375 -125);
FORCEPROP 1 LAST PART_NUMBER D97712-011
J 0
(-1375 -75);
DISPLAY 0.617021 (-1375 -75);
PAINT BLUE (-1375 -75);
FORCEPROP 1 LAST MATERIAL X6S
J 0
(-1375 -25);
DISPLAY 0.617021 (-1375 -25);
PAINT SKYBLUE (-1375 -25);
FORCEPROP 1 LASTPIN (-1425 175) $PN 1
J 0
(-1415 155);
DISPLAY 0.617021 (-1415 155);
PAINT ORANGE (-1415 155);
FORCEPROP 1 LAST VOLTAGE 16V
J 0
(-1375 75);
DISPLAY 0.617021 (-1375 75);
PAINT SKYBLUE (-1375 75);
FORCEPROP 1 LAST TOLERANCE 10%
J 0
(-1375 25);
DISPLAY 0.617021 (-1375 25);
PAINT SKYBLUE (-1375 25);
FORCEPROP 1 LAST LOCATION C1G28
J 0
(-1375 175);
DISPLAY 0.617021 (-1375 175);
PAINT AQUA (-1375 175);
FORCEPROP 1 LAST VALUE 1.0UF
J 0
(-1375 125);
DISPLAY 0.617021 (-1375 125);
PAINT SKYBLUE (-1375 125);
FORCEPROP 2 LAST CDS_LIB mstr_discrete
J 0
(-1425 75);
PAINT ORANGE (-1425 75);
DISPLAY INVISIBLE (-1425 75);
FORCEPROP 2 LAST ROOM VDDQ_GHJ_PWR_VR
J 0
(-1375 225);
DISPLAY 1.361702 (-1375 225);
PAINT ORANGE (-1375 225);
DISPLAY INVISIBLE (-1375 225);
FORCEPROP 1 LAST PATH I77
J 0
(-1375 225);
DISPLAY 1.319149 (-1375 225);
PAINT WHITE (-1375 225);
DISPLAY INVISIBLE (-1375 225);
FORCEPROP 2 LAST SEC 1
J 0
(-1375 300);
DISPLAY 0.680851 (-1375 300);
PAINT MONO (-1375 300);
DISPLAY INVISIBLE (-1375 300);
FORCEPROP 2 LAST SEC_TYPE 0402
J 0
(-1375 300);
DISPLAY 1.021277 (-1375 300);
PAINT ORANGE (-1375 300);
DISPLAY INVISIBLE (-1375 300);
FORCEADD CAP_A..1
(-1725 125);
FORCEPROP 1 LAST PACK_TYPE 0402V
J 0
(-1675 -75);
DISPLAY 0.617021 (-1675 -75);
PAINT SKYBLUE (-1675 -75);
FORCEPROP 1 LAST PART_NUMBER A36096-030
J 0
(-1675 -25);
DISPLAY 0.617021 (-1675 -25);
PAINT BLUE (-1675 -25);
FORCEPROP 1 LASTPIN (-1725 25) $PN 2
J 0
(-1715 5);
DISPLAY 0.617021 (-1715 5);
PAINT ORANGE (-1715 5);
FORCEPROP 1 LASTPIN (-1725 225) $PN 1
J 0
(-1715 205);
DISPLAY 0.617021 (-1715 205);
PAINT ORANGE (-1715 205);
FORCEPROP 1 LAST VOLTAGE 16V
J 0
(-1675 125);
DISPLAY 0.617021 (-1675 125);
PAINT SKYBLUE (-1675 125);
FORCEPROP 1 LAST VALUE 0.1UF
J 0
(-1675 175);
DISPLAY 0.617021 (-1675 175);
PAINT SKYBLUE (-1675 175);
FORCEPROP 1 LAST LOCATION C1F28
J 0
(-1675 225);
DISPLAY 0.617021 (-1675 225);
PAINT AQUA (-1675 225);
FORCEPROP 1 LAST TOLERANCE 10%
J 0
(-1675 75);
DISPLAY 0.617021 (-1675 75);
PAINT SKYBLUE (-1675 75);
FORCEPROP 1 LAST MATERIAL X7R
J 0
(-1675 25);
DISPLAY 0.617021 (-1675 25);
PAINT SKYBLUE (-1675 25);
FORCEPROP 2 LAST CDS_LIB dev_discrete
J 0
(-1725 125);
PAINT ORANGE (-1725 125);
DISPLAY INVISIBLE (-1725 125);
FORCEPROP 1 LAST PATH I78
J 0
(-1675 275);
DISPLAY 0.978723 (-1675 275);
PAINT WHITE (-1675 275);
DISPLAY INVISIBLE (-1675 275);
FORCEPROP 2 LAST ROOM VDDQ_GHJ_PWR_VR
J 0
(-1675 275);
DISPLAY 1.361702 (-1675 275);
PAINT ORANGE (-1675 275);
DISPLAY INVISIBLE (-1675 275);
FORCEPROP 2 LAST CDS_SEC 1
J 0
(-1675 275);
PAINT ORANGE (-1675 275);
DISPLAY INVISIBLE (-1675 275);
FORCEPROP 2 LAST SEC_TYPE 0402V
J 0
(-1675 350);
DISPLAY 1.021277 (-1675 350);
PAINT ORANGE (-1675 350);
DISPLAY INVISIBLE (-1675 350);
FORCEPROP 2 LAST SEC 1
J 0
(-1675 350);
DISPLAY 0.680851 (-1675 350);
PAINT MONO (-1675 350);
DISPLAY INVISIBLE (-1675 350);
FORCEADD CAP..1
(-1975 100);
FORCEPROP 1 LAST PACK_TYPE 0402
J 0
(-1925 -100);
DISPLAY 0.617021 (-1925 -100);
PAINT SKYBLUE (-1925 -100);
FORCEPROP 1 LAST PART_NUMBER D97712-011
J 0
(-1925 -50);
DISPLAY 0.617021 (-1925 -50);
PAINT BLUE (-1925 -50);
FORCEPROP 1 LASTPIN (-1975 0) $PN 2
J 0
(-1965 -20);
DISPLAY 0.617021 (-1965 -20);
PAINT ORANGE (-1965 -20);
FORCEPROP 1 LAST MATERIAL X6S
J 0
(-1925 0);
DISPLAY 0.617021 (-1925 0);
PAINT SKYBLUE (-1925 0);
FORCEPROP 1 LAST TOLERANCE 10%
J 0
(-1925 50);
DISPLAY 0.617021 (-1925 50);
PAINT SKYBLUE (-1925 50);
FORCEPROP 1 LAST VOLTAGE 16V
J 0
(-1925 100);
DISPLAY 0.617021 (-1925 100);
PAINT SKYBLUE (-1925 100);
FORCEPROP 1 LASTPIN (-1975 200) $PN 1
J 0
(-1965 180);
DISPLAY 0.617021 (-1965 180);
PAINT ORANGE (-1965 180);
FORCEPROP 1 LAST LOCATION C1G13
J 0
(-1925 200);
DISPLAY 0.617021 (-1925 200);
PAINT AQUA (-1925 200);
FORCEPROP 1 LAST VALUE 1.0UF
J 0
(-1925 150);
DISPLAY 0.617021 (-1925 150);
PAINT SKYBLUE (-1925 150);
FORCEPROP 2 LAST CDS_LIB mstr_discrete
J 0
(-1975 100);
PAINT ORANGE (-1975 100);
DISPLAY INVISIBLE (-1975 100);
FORCEPROP 2 LAST CDS_LOCATION C1G13
J 0
(-1925 200);
DISPLAY 0.617021 (-1925 200);
PAINT AQUA (-1925 200);
DISPLAY INVISIBLE (-1925 200);
FORCEPROP 1 LAST PATH I79
J 0
(-1925 250);
DISPLAY 1.319149 (-1925 250);
PAINT WHITE (-1925 250);
DISPLAY INVISIBLE (-1925 250);
FORCEPROP 2 LAST ROOM VDDQ_GHJ_PWR_VR
J 0
(-1925 250);
DISPLAY 1.361702 (-1925 250);
PAINT ORANGE (-1925 250);
DISPLAY INVISIBLE (-1925 250);
FORCEPROP 2 LAST SEC_TYPE 0402
J 0
(-1925 325);
DISPLAY 1.021277 (-1925 325);
PAINT ORANGE (-1925 325);
DISPLAY INVISIBLE (-1925 325);
FORCEPROP 2 LAST SEC 1
J 0
(-1925 325);
DISPLAY 0.680851 (-1925 325);
PAINT MONO (-1925 325);
DISPLAY INVISIBLE (-1925 325);
FORCEADD CAP..1
(-2225 100);
FORCEPROP 1 LAST PACK_TYPE 0805
J 0
(-2175 -100);
DISPLAY 0.617021 (-2175 -100);
PAINT SKYBLUE (-2175 -100);
FORCEPROP 1 LAST PART_NUMBER C95333-007
J 0
(-2175 -50);
DISPLAY 0.617021 (-2175 -50);
PAINT BLUE (-2175 -50);
FORCEPROP 1 LASTPIN (-2225 0) $PN 2
J 0
(-2215 -20);
DISPLAY 0.617021 (-2215 -20);
PAINT ORANGE (-2215 -20);
FORCEPROP 1 LAST MATERIAL X6S
J 0
(-2175 0);
DISPLAY 0.617021 (-2175 0);
PAINT SKYBLUE (-2175 0);
FORCEPROP 1 LAST LOCATION C9U3
J 0
(-2175 200);
DISPLAY 0.617021 (-2175 200);
PAINT AQUA (-2175 200);
FORCEPROP 1 LAST VALUE 10UF
J 0
(-2175 150);
DISPLAY 0.617021 (-2175 150);
PAINT SKYBLUE (-2175 150);
FORCEPROP 1 LAST TOLERANCE 10%
J 0
(-2175 50);
DISPLAY 0.617021 (-2175 50);
PAINT SKYBLUE (-2175 50);
FORCEPROP 1 LAST VOLTAGE 16V
J 0
(-2175 100);
DISPLAY 0.617021 (-2175 100);
PAINT SKYBLUE (-2175 100);
FORCEPROP 1 LASTPIN (-2225 200) $PN 1
J 0
(-2215 180);
DISPLAY 0.617021 (-2215 180);
PAINT ORANGE (-2215 180);
FORCEPROP 2 LAST CDS_LIB mstr_discrete
J 0
(-2225 100);
PAINT ORANGE (-2225 100);
DISPLAY INVISIBLE (-2225 100);
FORCEPROP 2 LAST CDS_LOCATION C9U3
J 0
(-2175 200);
DISPLAY 0.617021 (-2175 200);
PAINT AQUA (-2175 200);
DISPLAY INVISIBLE (-2175 200);
FORCEPROP 1 LAST PATH I80
J 0
(-2175 250);
DISPLAY 1.319149 (-2175 250);
PAINT WHITE (-2175 250);
DISPLAY INVISIBLE (-2175 250);
FORCEPROP 2 LAST ROOM VDDQ_GHJ_PWR_VR
J 0
(-2175 250);
DISPLAY 1.361702 (-2175 250);
PAINT ORANGE (-2175 250);
DISPLAY INVISIBLE (-2175 250);
FORCEPROP 2 LAST SEC_TYPE 0805
J 0
(-2175 325);
DISPLAY 1.021277 (-2175 325);
PAINT ORANGE (-2175 325);
DISPLAY INVISIBLE (-2175 325);
FORCEPROP 2 LAST SEC 1
J 0
(-2175 325);
DISPLAY 0.680851 (-2175 325);
PAINT MONO (-2175 325);
DISPLAY INVISIBLE (-2175 325);
FORCEADD CAP..1
(-2475 150);
FORCEPROP 1 LAST PACK_TYPE 0805
J 0
(-2425 -50);
DISPLAY 0.617021 (-2425 -50);
PAINT SKYBLUE (-2425 -50);
FORCEPROP 1 LAST PART_NUMBER C95333-007
J 0
(-2425 0);
DISPLAY 0.617021 (-2425 0);
PAINT BLUE (-2425 0);
FORCEPROP 1 LASTPIN (-2475 250) $PN 1
J 0
(-2465 230);
DISPLAY 0.617021 (-2465 230);
PAINT ORANGE (-2465 230);
FORCEPROP 1 LASTPIN (-2475 50) $PN 2
J 0
(-2465 30);
DISPLAY 0.617021 (-2465 30);
PAINT ORANGE (-2465 30);
FORCEPROP 1 LAST MATERIAL X6S
J 0
(-2425 50);
DISPLAY 0.617021 (-2425 50);
PAINT SKYBLUE (-2425 50);
FORCEPROP 1 LAST VOLTAGE 16V
J 0
(-2425 150);
DISPLAY 0.617021 (-2425 150);
PAINT SKYBLUE (-2425 150);
FORCEPROP 1 LAST VALUE 10UF
J 0
(-2425 200);
DISPLAY 0.617021 (-2425 200);
PAINT SKYBLUE (-2425 200);
FORCEPROP 1 LAST TOLERANCE 10%
J 0
(-2425 100);
DISPLAY 0.617021 (-2425 100);
PAINT SKYBLUE (-2425 100);
FORCEPROP 1 LAST LOCATION C9T6
J 0
(-2425 250);
DISPLAY 0.617021 (-2425 250);
PAINT AQUA (-2425 250);
FORCEPROP 2 LAST CDS_LIB mstr_discrete
J 0
(-2475 150);
PAINT ORANGE (-2475 150);
DISPLAY INVISIBLE (-2475 150);
FORCEPROP 2 LAST CDS_LOCATION C9T6
J 0
(-2425 250);
DISPLAY 0.617021 (-2425 250);
PAINT AQUA (-2425 250);
DISPLAY INVISIBLE (-2425 250);
FORCEPROP 2 LAST SEC_TYPE 0805
J 0
(-2425 375);
DISPLAY 1.021277 (-2425 375);
PAINT ORANGE (-2425 375);
DISPLAY INVISIBLE (-2425 375);
FORCEPROP 2 LAST SEC 1
J 0
(-2425 375);
DISPLAY 0.680851 (-2425 375);
PAINT MONO (-2425 375);
DISPLAY INVISIBLE (-2425 375);
FORCEPROP 1 LAST PATH I81
J 0
(-2425 300);
DISPLAY 1.319149 (-2425 300);
PAINT WHITE (-2425 300);
DISPLAY INVISIBLE (-2425 300);
FORCEPROP 2 LAST ROOM VDDQ_GHJ_PWR_VR
J 0
(-2425 300);
DISPLAY 1.361702 (-2425 300);
PAINT ORANGE (-2425 300);
DISPLAY INVISIBLE (-2425 300);
FORCEADD OFFPAGE..1
(-1825 -225);
FORCEPROP 2 LAST $XR0 223 
J 0
(-2077 -225);
DISPLAY 0.638298 (-2077 -225);
PAINT MONO (-2077 -225);
FORCEPROP 2 LAST ROOM VDDQ_GHJ_PWR_VR
J 0
(-2225 -150);
DISPLAY 1.936170 (-2225 -150);
PAINT ORANGE (-2225 -150);
DISPLAY INVISIBLE (-2225 -150);
FORCEPROP 2 LAST BOM_COST VDDQ_GHJ_PWR_VR
J 0
(-2075 -175);
DISPLAY 1.446809 (-2075 -175);
PAINT MONO (-2075 -175);
DISPLAY INVISIBLE (-2075 -175);
FORCEPROP 2 LAST CDS_LIB mstr_standard
J 0
(-1825 -225);
PAINT ORANGE (-1825 -225);
DISPLAY INVISIBLE (-1825 -225);
FORCEPROP 2 LAST PATH I82
J 0
(-1770 -150);
DISPLAY 1.361702 (-1770 -150);
PAINT ORANGE (-1770 -150);
DISPLAY INVISIBLE (-1770 -150);
FORCEPROP 1 LAST COMMENT_BODY TRUE
J 0
(-1700 -325);
DISPLAY 1.680851 (-1700 -325);
PAINT GREEN (-1700 -325);
DISPLAY INVISIBLE (-1700 -325);
FORCEPROP 1 LAST OFFPAGE TRUE
J 0
(-1500 -350);
DISPLAY 1.680851 (-1500 -350);
PAINT GREEN (-1500 -350);
DISPLAY INVISIBLE (-1500 -350);
FORCEADD VCC_CORE..1
(-2725 600);
FORCEPROP 3 LASTPIN (-2725 550) SIG_NAME VR_FET_SW_P12V_STBY_PVDDQ_GHJ\g
J 0
(-2715 560);
DISPLAY 0.659574 (-2715 560);
PAINT MONO (-2715 560);
DISPLAY INVISIBLE (-2715 560);
FORCEPROP 1 LAST HDL_POWER VR_FET_SW_P12V_STBY_PVDDQ_GHJ
J 1
(-2550 650);
DISPLAY 0.617021 (-2550 650);
PAINT GREEN (-2550 650);
FORCEPROP 1 LAST PATH I83
J 0
(-2675 625);
DISPLAY 1.170213 (-2675 625);
PAINT AQUA (-2675 625);
DISPLAY INVISIBLE (-2675 625);
FORCEPROP 2 LAST CDS_LIB mstr_symbols
J 0
(-2725 600);
PAINT ORANGE (-2725 600);
DISPLAY INVISIBLE (-2725 600);
FORCEADD CAP..1
(-2725 125);
FORCEPROP 1 LAST PACK_TYPE 0805
J 0
(-2675 -75);
DISPLAY 0.617021 (-2675 -75);
PAINT SKYBLUE (-2675 -75);
FORCEPROP 1 LAST PART_NUMBER C95333-007
J 0
(-2675 -25);
DISPLAY 0.617021 (-2675 -25);
PAINT BLUE (-2675 -25);
FORCEPROP 1 LASTPIN (-2725 225) $PN 1
J 0
(-2715 205);
DISPLAY 0.617021 (-2715 205);
PAINT ORANGE (-2715 205);
FORCEPROP 1 LASTPIN (-2725 25) $PN 2
J 0
(-2715 5);
DISPLAY 0.617021 (-2715 5);
PAINT ORANGE (-2715 5);
FORCEPROP 1 LAST MATERIAL X6S
J 0
(-2675 25);
DISPLAY 0.617021 (-2675 25);
PAINT SKYBLUE (-2675 25);
FORCEPROP 1 LAST VOLTAGE 16V
J 0
(-2675 125);
DISPLAY 0.617021 (-2675 125);
PAINT SKYBLUE (-2675 125);
FORCEPROP 1 LAST TOLERANCE 10%
J 0
(-2675 75);
DISPLAY 0.617021 (-2675 75);
PAINT SKYBLUE (-2675 75);
FORCEPROP 1 LAST VALUE 10UF
J 0
(-2675 175);
DISPLAY 0.617021 (-2675 175);
PAINT SKYBLUE (-2675 175);
FORCEPROP 1 LAST LOCATION C9T9
J 0
(-2675 225);
DISPLAY 0.617021 (-2675 225);
PAINT AQUA (-2675 225);
FORCEPROP 2 LAST CDS_LIB mstr_discrete
J 0
(-2725 125);
PAINT ORANGE (-2725 125);
DISPLAY INVISIBLE (-2725 125);
FORCEPROP 2 LAST ROOM VDDQ_GHJ_PWR_VR
J 0
(-2675 275);
DISPLAY 1.361702 (-2675 275);
PAINT ORANGE (-2675 275);
DISPLAY INVISIBLE (-2675 275);
FORCEPROP 1 LAST PATH I84
J 0
(-2675 275);
DISPLAY 1.319149 (-2675 275);
PAINT WHITE (-2675 275);
DISPLAY INVISIBLE (-2675 275);
FORCEPROP 2 LAST SEC_TYPE 0805
J 0
(-2675 350);
DISPLAY 1.021277 (-2675 350);
PAINT ORANGE (-2675 350);
DISPLAY INVISIBLE (-2675 350);
FORCEPROP 2 LAST SEC 1
J 0
(-2675 350);
DISPLAY 0.680851 (-2675 350);
PAINT MONO (-2675 350);
DISPLAY INVISIBLE (-2675 350);
FORCEADD GND..1
(-2725 -250);
FORCEPROP 3 LASTPIN (-2725 -200) SIG_NAME GND\g
J 0
(-2715 -190);
DISPLAY 0.659574 (-2715 -190);
PAINT MONO (-2715 -190);
DISPLAY INVISIBLE (-2715 -190);
FORCEPROP 2 LAST ROOM VDDQ_GHJ_PWR_VR
J 0
(-3275 -175);
DISPLAY 1.936170 (-3275 -175);
PAINT ORANGE (-3275 -175);
DISPLAY INVISIBLE (-3275 -175);
FORCEPROP 2 LAST BOM_COST VDDQ_GHJ_PWR_VR
J 0
(-3100 -175);
DISPLAY 1.446809 (-3100 -175);
PAINT MONO (-3100 -175);
DISPLAY INVISIBLE (-3100 -175);
FORCEPROP 1 LAST BODY_TYPE PLUMBING
J 0
(-2770 -293);
DISPLAY 0.340426 (-2770 -293);
PAINT GREEN (-2770 -293);
DISPLAY INVISIBLE (-2770 -293);
FORCEPROP 1 LAST SIZE 1B
J 0
(-2650 -300);
DISPLAY 1.723404 (-2650 -300);
PAINT GREEN (-2650 -300);
DISPLAY INVISIBLE (-2650 -300);
FORCEPROP 1 LAST VOLTAGE 0
J 0
(-2725 -250);
PAINT SKYBLUE (-2725 -250);
DISPLAY INVISIBLE (-2725 -250);
FORCEPROP 2 LAST CDS_LIB mstr_symbols
J 0
(-2725 -250);
PAINT ORANGE (-2725 -250);
DISPLAY INVISIBLE (-2725 -250);
FORCEPROP 1 LAST HDL_POWER GND
J 0
(-2725 -100);
DISPLAY 1.723404 (-2725 -100);
PAINT GREEN (-2725 -100);
DISPLAY INVISIBLE (-2725 -100);
FORCEPROP 1 LAST PATH I85
J 0
(-2650 -250);
DISPLAY 1.170213 (-2650 -250);
PAINT AQUA (-2650 -250);
DISPLAY INVISIBLE (-2650 -250);
FORCEADD P5V_STBY..1
(0 3150);
FORCEPROP 3 LASTPIN (0 3100) SIG_NAME P5V_STBY\g
J 0
(10 3110);
DISPLAY 0.659574 (10 3110);
PAINT MONO (10 3110);
DISPLAY INVISIBLE (10 3110);
FORCEPROP 1 LAST HDL_POWER P5V_STBY
J 0
(-300 3025);
DISPLAY 0.872340 (-300 3025);
PAINT ORANGE (-300 3025);
DISPLAY INVISIBLE (-300 3025);
FORCEPROP 1 LAST BODY_TYPE PLUMBING
J 0
(-45 3107);
DISPLAY 0.340426 (-45 3107);
PAINT GREEN (-45 3107);
DISPLAY INVISIBLE (-45 3107);
FORCEPROP 1 LAST VOLTAGE 5.0V
J 0
(-45 3107);
DISPLAY 0.340426 (-45 3107);
PAINT SKYBLUE (-45 3107);
DISPLAY INVISIBLE (-45 3107);
FORCEPROP 2 LAST CDS_LIB mstr_symbols
J 0
(0 3150);
PAINT ORANGE (0 3150);
DISPLAY INVISIBLE (0 3150);
FORCEPROP 1 LAST PATH I87
J 0
(45 3152);
DISPLAY 0.340426 (45 3152);
PAINT GREEN (45 3152);
DISPLAY INVISIBLE (45 3152);
FORCEPROP 1 LAST SIZE 1B
J 0
(45 3172);
DISPLAY 0.340426 (45 3172);
PAINT GREEN (45 3172);
DISPLAY INVISIBLE (45 3172);
FORCEADD P5V_STBY..1
(200 800);
FORCEPROP 3 LASTPIN (200 750) SIG_NAME P5V_STBY\g
J 0
(210 760);
DISPLAY 0.659574 (210 760);
PAINT MONO (210 760);
DISPLAY INVISIBLE (210 760);
FORCEPROP 1 LAST HDL_POWER P5V_STBY
J 0
(-100 675);
DISPLAY 0.872340 (-100 675);
PAINT ORANGE (-100 675);
DISPLAY INVISIBLE (-100 675);
FORCEPROP 1 LAST VOLTAGE 5.0V
J 0
(155 757);
DISPLAY 0.340426 (155 757);
PAINT SKYBLUE (155 757);
DISPLAY INVISIBLE (155 757);
FORCEPROP 1 LAST BODY_TYPE PLUMBING
J 0
(155 757);
DISPLAY 0.340426 (155 757);
PAINT GREEN (155 757);
DISPLAY INVISIBLE (155 757);
FORCEPROP 1 LAST SIZE 1B
J 0
(245 822);
DISPLAY 0.340426 (245 822);
PAINT GREEN (245 822);
DISPLAY INVISIBLE (245 822);
FORCEPROP 2 LAST CDS_LIB mstr_symbols
J 0
(200 800);
PAINT ORANGE (200 800);
DISPLAY INVISIBLE (200 800);
FORCEPROP 1 LAST PATH I88
J 0
(245 802);
DISPLAY 0.340426 (245 802);
PAINT GREEN (245 802);
DISPLAY INVISIBLE (245 802);
FORCEADD VCC_CORE..1
(-2700 2900);
FORCEPROP 3 LASTPIN (-2700 2850) SIG_NAME VR_FET_SW_P12V_STBY_PVDDQ_GHJ\g
J 0
(-2690 2860);
DISPLAY 0.659574 (-2690 2860);
PAINT MONO (-2690 2860);
DISPLAY INVISIBLE (-2690 2860);
FORCEPROP 1 LAST HDL_POWER VR_FET_SW_P12V_STBY_PVDDQ_GHJ
J 1
(-2625 2950);
DISPLAY 0.617021 (-2625 2950);
PAINT GREEN (-2625 2950);
FORCEPROP 1 LAST PATH I89
J 0
(-2650 2925);
DISPLAY 0.872340 (-2650 2925);
PAINT AQUA (-2650 2925);
DISPLAY INVISIBLE (-2650 2925);
FORCEPROP 2 LAST CDS_LIB mstr_symbols
J 0
(-2700 2900);
PAINT ORANGE (-2700 2900);
DISPLAY INVISIBLE (-2700 2900);
FORCEADD DNS..2
(4305 20);
PAINT RED (4305 20);
FORCEPROP 1 LAST COMMENT_BODY TRUE
R 1
J 0
(4380 -205);
DISPLAY 0.872340 (4380 -205);
PAINT GREEN (4380 -205);
DISPLAY INVISIBLE (4380 -205);
FORCEPROP 2 LAST CDS_LIB mstr_misc
J 0
(4305 20);
PAINT ORANGE (4305 20);
DISPLAY INVISIBLE (4305 20);
FORCEADD DNS..2
(4280 2395);
PAINT RED (4280 2395);
FORCEPROP 1 LAST COMMENT_BODY TRUE
R 1
J 0
(4355 2170);
DISPLAY 0.872340 (4355 2170);
PAINT GREEN (4355 2170);
DISPLAY INVISIBLE (4355 2170);
FORCEPROP 2 LAST CDS_LIB mstr_misc
J 0
(4280 2395);
PAINT ORANGE (4280 2395);
DISPLAY INVISIBLE (4280 2395);
FORCEADD INTEL_CORP_BPAGE..1
(4925 -1575);
FORCEPROP 1 LAST CDS_CON_LAST_MODIFIED Tue Dec 01 11:52:27 2015
J 0
(3500 -1250);
DISPLAY 1.936170 (3500 -1250);
PAINT GREEN (3500 -1250);
DISPLAY INVISIBLE (3500 -1250);
FORCEPROP 1 LAST CUSTOM_TXT_CDS <CURRENT_DESIGN_SHEET> OF <TOTAL_DESIGN_SHEETS>
J 0
(4425 -1550);
PAINT GREEN (4425 -1550);
FORCEPROP 1 LAST CUSTOM_TXT_CDS <CON_LAST_MODIFIED>
J 0
(3000 -1225);
PAINT GREEN (3000 -1225);
FORCEPROP 2 LAST CUSTOM_TXT_CDS <XR_PAGE_TITLE>
J 0
(-2965 3675);
DISPLAY 0.638298 (-2965 3675);
PAINT PINK (-2965 3675);
DISPLAY INVISIBLE (-2965 3675);
FORCEPROP 1 LAST SCH_DEPT BESD
J 1
(475 -1475);
DISPLAY 1.212766 (475 -1475);
PAINT YELLOW (475 -1475);
FORCEPROP 1 LAST SCH_TITLE VDDQ GHJ VR(2 OF 3)
J 0
(-3025 -1525);
DISPLAY 1.212766 (-3025 -1525);
PAINT ORANGE (-3025 -1525);
FORCEPROP 1 LAST SCH_ADDRESS3 Santa Clara, CA 95052-8119
J 0
(950 -1550);
DISPLAY 0.617021 (950 -1550);
PAINT GREEN (950 -1550);
FORCEPROP 1 LAST SCH_NUMBER H4694802
J 0
(3625 -1425);
DISPLAY 1.212766 (3625 -1425);
PAINT YELLOW (3625 -1425);
FORCEPROP 1 LAST SCH_REV 2.420
J 0
(4675 -1425);
DISPLAY 0.978723 (4675 -1425);
PAINT YELLOW (4675 -1425);
FORCEPROP 1 LAST SCH_ADDRESS1 2200 Mission College Blvd.
J 0
(950 -1450);
DISPLAY 0.617021 (950 -1450);
PAINT GREEN (950 -1450);
FORCEPROP 1 LAST SCH_ADDRESS2 P.O. BOX 58119
J 0
(950 -1500);
DISPLAY 0.617021 (950 -1500);
PAINT GREEN (950 -1500);
FORCEPROP 2 LAST ROOM VDDQ_GHJ_PWR_VR
J 0
(-3175 3525);
DISPLAY 1.936170 (-3175 3525);
PAINT ORANGE (-3175 3525);
DISPLAY INVISIBLE (-3175 3525);
FORCEPROP 2 LAST PAGE_BORDER TRUE
J 0
(-2965 3675);
DISPLAY 1.255319 (-2965 3675);
PAINT PINK (-2965 3675);
DISPLAY INVISIBLE (-2965 3675);
FORCEPROP 1 LAST COMMENT_BODY TRUE
J 0
(4937 -1563);
DISPLAY 0.893617 (4937 -1563);
PAINT GREEN (4937 -1563);
DISPLAY INVISIBLE (4937 -1563);
FORCEPROP 2 LAST CDS_LIB mstr_symbols
J 0
(4925 -1575);
DISPLAY 1.936170 (4925 -1575);
PAINT ORANGE (4925 -1575);
DISPLAY INVISIBLE (4925 -1575);
FORCEPROP 2 LAST CDS_XR_PAGE_TITLE CR-224 : @BASEBOARD_FAB2_LIB.BASEBOARD_FAB2(SCH_1):PAGE224
J 0
(-2965 3675);
DISPLAY 0.638298 (-2965 3675);
PAINT PINK (-2965 3675);
DISPLAY INVISIBLE (-2965 3675);
WIRE 16 -1 (975 2400)(850 2400);
WIRE 16 -1 (850 2400)(850 1200);
WIRE 16 -1 (850 1200)(3575 1200);
WIRE 16 -1 (3575 1200)(3575 1950);
WIRE 16 -1 (3200 1950)(3575 1950);
WIRE 16 -1 (4000 1950)(3575 1950);
WIRE 16 -1 (4000 1850)(4000 1950);
WIRE 16 -1 (4000 1950)(4000 2000);
WIRE 16 -1 (4275 2150)(4275 2300);
WIRE 16 -1 (4300 -225)(4300 -75);
WIRE 16 -1 (700 1625)(700 1525);
WIRE 16 -1 (2700 1375)(2700 1325);
WIRE 16 -1 (2600 2125)(2600 2075);
WIRE 16 -1 (800 -725)(800 -825);
WIRE 16 -1 (2800 -1000)(2800 -1050);
WIRE 16 -1 (2700 -175)(2700 -250);
WIRE 16 -1 (1975 1850)(2325 1850);
WIRE 16 -1 (2325 1800)(2325 1850);
WIRE 16 -1 (2325 1750)(2325 1800);
WIRE 16 -1 (2325 1800)(1975 1800);
WIRE 16 -1 (2325 1700)(2325 1750);
WIRE 16 -1 (2325 1750)(1975 1750);
WIRE 16 -1 (2325 1550)(2325 1700);
WIRE 16 -1 (2325 1700)(1975 1700);
WIRE 16 -1 (-400 2400)(-400 2200);
WIRE 16 -1 (-400 2200)(-525 2200);
WIRE 16 -1 (-525 2400)(-525 2200);
WIRE 16 -1 (-525 2200)(-1375 2200);
WIRE 16 -1 (-1375 2450)(-1375 2200);
WIRE 16 -1 (-1375 2200)(-1675 2200);
WIRE 16 -1 (-1675 2400)(-1675 2200);
WIRE 16 -1 (-1675 2200)(-1925 2200);
WIRE 16 -1 (-1925 2350)(-1925 2200);
WIRE 16 -1 (-1925 2200)(-2175 2200);
WIRE 16 -1 (-2175 2450)(-2175 2200);
WIRE 16 -1 (-2450 2200)(-2175 2200);
WIRE 16 -1 (-2450 2450)(-2450 2200);
WIRE 16 -1 (-2700 2200)(-2450 2200);
WIRE 16 -1 (-2700 2425)(-2700 2200);
WIRE 16 -1 (-2700 2125)(-2700 2200);
WIRE 16 -1 (1000 25)(875 25);
WIRE 16 -1 (875 25)(875 -1150);
WIRE 16 -1 (875 -1150)(3525 -1150);
WIRE 16 -1 (3525 -1150)(3525 -425);
WIRE 16 -1 (3200 -425)(3525 -425);
WIRE 16 -1 (3525 -425)(4000 -425);
WIRE 16 -1 (4000 -525)(4000 -425);
WIRE 16 -1 (4000 -425)(4000 -375);
WIRE 16 -1 (4000 -800)(4000 -725);
WIRE 16 -1 (4000 1575)(4000 1650);
WIRE 16 -1 (2000 -525)(2325 -525);
WIRE 16 -1 (2325 -575)(2325 -525);
WIRE 16 -1 (2325 -625)(2325 -575);
WIRE 16 -1 (2325 -575)(2000 -575);
WIRE 16 -1 (2325 -675)(2325 -625);
WIRE 16 -1 (2325 -625)(2000 -625);
WIRE 16 -1 (2325 -825)(2325 -675);
WIRE 16 -1 (2325 -675)(2000 -675);
WIRE 16 -1 (1000 375)(725 375);
WIRE 16 -1 (725 375)(725 325);
WIRE 16 -1 (1000 325)(725 325);
WIRE 16 -1 (725 325)(-1725 325);
WIRE 16 -1 (-1725 225)(-1725 325);
WIRE 16 -1 (-1725 325)(-1975 325);
WIRE 16 -1 (-1975 200)(-1975 325);
WIRE 16 -1 (-1975 325)(-2225 325);
WIRE 16 -1 (-2225 200)(-2225 325);
WIRE 16 -1 (-2225 325)(-2475 325);
WIRE 16 -1 (-2475 250)(-2475 325);
WIRE 16 -1 (-2475 325)(-2725 325);
WIRE 16 -1 (-2725 225)(-2725 325);
WIRE 16 -1 (-2725 550)(-2725 325);
WIRE 16 -1 (-475 50)(-475 -150);
WIRE 16 -1 (-475 -150)(-575 -150);
WIRE 16 -1 (-575 50)(-575 -150);
WIRE 16 -1 (-575 -150)(-1425 -150);
WIRE 16 -1 (-1425 -25)(-1425 -150);
WIRE 16 -1 (-1425 -150)(-1725 -150);
WIRE 16 -1 (-1725 25)(-1725 -150);
WIRE 16 -1 (-1725 -150)(-1975 -150);
WIRE 16 -1 (-1975 0)(-1975 -150);
WIRE 16 -1 (-1975 -150)(-2225 -150);
WIRE 16 -1 (-2225 0)(-2225 -150);
WIRE 16 -1 (-2225 -150)(-2475 -150);
WIRE 16 -1 (-2475 50)(-2475 -150);
WIRE 16 -1 (-2475 -150)(-2725 -150);
WIRE 16 -1 (-2725 25)(-2725 -150);
WIRE 16 -1 (-2725 -200)(-2725 -150);
WIRE 16 -1 (975 2500)(825 2500);
WIRE 16 -1 (825 2500)(825 2600);
WIRE 16 -1 (975 2600)(825 2600);
WIRE 16 -1 (825 2600)(0 2600);
WIRE 16 -1 (0 2600)(0 3050);
WIRE 16 -1 (-400 3050)(0 3050);
WIRE 16 -1 (0 3050)(0 3100);
WIRE 16 -1 (-525 3050)(-400 3050);
WIRE 16 -1 (-400 2600)(-400 3050);
WIRE 16 -1 (-525 2600)(-525 3050);
WIRE 16 -1 (-1025 3050)(-525 3050);
WIRE 16 -1 (1000 125)(925 125);
WIRE 16 -1 (925 125)(925 225);
WIRE 16 -1 (925 225)(1000 225);
WIRE 16 -1 (200 225)(925 225);
WIRE 16 -1 (200 675)(200 225);
WIRE 16 -1 (200 675)(-475 675);
WIRE 16 -1 (200 675)(200 750);
WIRE 16 -1 (-475 675)(-575 675);
WIRE 16 -1 (-475 250)(-475 675);
WIRE 16 -1 (-575 250)(-575 675);
WIRE 16 -1 (-575 675)(-1075 675);
WIRE 16 -1 (975 2750)(725 2750);
WIRE 16 -1 (725 2750)(725 2700);
WIRE 16 -1 (975 2700)(725 2700);
WIRE 16 -1 (725 2700)(-1675 2700);
WIRE 16 -1 (-1675 2600)(-1675 2700);
WIRE 16 -1 (-1675 2700)(-1925 2700);
WIRE 16 -1 (-1925 2550)(-1925 2700);
WIRE 16 -1 (-1925 2700)(-2175 2700);
WIRE 16 -1 (-2175 2650)(-2175 2700);
WIRE 16 -1 (-2450 2700)(-2175 2700);
WIRE 16 -1 (-2450 2650)(-2450 2700);
WIRE 16 -1 (-2700 2700)(-2450 2700);
WIRE 16 -1 (-2700 2625)(-2700 2700);
WIRE 16 -1 (-2700 2850)(-2700 2700);
WIRE 16 2175 (-925 300)(-225 300);
WIRE 16 2175 (-925 300)(-925 -75);
WIRE 16 2175 (-225 300)(-225 -75);
WIRE 16 2175 (-925 -75)(-225 -75);
WIRE 3 2175 (2525 -450)(2950 -450);
WIRE 3 2175 (2525 -450)(2525 -1125);
WIRE 3 2175 (2950 -450)(2950 -1125);
WIRE 3 2175 (2525 -1125)(2950 -1125);
WIRE 3 2175 (2475 125)(2950 125);
WIRE 3 2175 (2475 125)(2475 -350);
WIRE 3 2175 (2950 125)(2950 -350);
WIRE 3 2175 (2475 -350)(2950 -350);
WIRE 16 -1 (2000 -425)(2800 -425);
FORCEPROP 2 LAST SIG_NAME VR_PVDDQ_GHJ_PH2_SW
J 0
(2360 -415);
DISPLAY 0.617021 (2360 -415);
PAINT ORANGE (2360 -415);
FORCEPROP 2 LASTPROP $XRERR UNIQUE?
J 0
(2120 -415);
DISPLAY 0.638298 (2120 -415);
PAINT MONO (2120 -415);
DISPLAY INVISIBLE (2120 -415);
WIRE 16 -1 (2800 -425)(3000 -425);
WIRE 16 -1 (2800 -500)(2800 -425);
WIRE 16 -1 (1000 -325)(800 -325);
WIRE 16 -1 (800 -325)(800 775);
WIRE 16 -1 (800 -525)(800 -325);
WIRE 16 -1 (800 775)(3575 775);
FORCEPROP 2 LAST SIG_NAME VR_PVDDQ_GHJ_AIREF2
J 0
(2235 789);
DISPLAY 0.617021 (2235 789);
PAINT ORANGE (2235 789);
WIRE 3 2175 (450 1450)(1050 1450);
WIRE 3 2175 (450 2025)(450 1450);
WIRE 3 2175 (1050 2025)(1050 1450);
WIRE 3 2175 (450 2025)(1050 2025);
WIRE 16 -1 (-1425 675)(-1275 675);
WIRE 16 -1 (-1425 675)(-1425 425);
WIRE 16 -1 (-1425 425)(1000 425);
FORCEPROP 2 LAST SIG_NAME VR_PVDDQ_GHJ_PH2_VCIN
J 0
(-1340 435);
DISPLAY 0.617021 (-1340 435);
PAINT ORANGE (-1340 435);
FORCEPROP 2 LASTPROP $XRERR UNIQUE?
J 0
(-1580 435);
DISPLAY 0.638298 (-1580 435);
PAINT MONO (-1580 435);
DISPLAY INVISIBLE (-1580 435);
WIRE 16 -1 (-1425 175)(-1425 425);
WIRE 3 2175 (2325 2450)(2850 2450);
WIRE 3 2175 (2325 2450)(2325 2000);
WIRE 3 2175 (2850 2450)(2850 2000);
WIRE 3 2175 (2325 2000)(2850 2000);
WIRE 16 -1 (-975 -650)(750 -650);
FORCEPROP 2 LAST SIG_NAME VR_PVDDQ_GHJ_PH2_PHASE
J 0
(-865 -640);
DISPLAY 0.617021 (-865 -640);
PAINT ORANGE (-865 -640);
FORCEPROP 2 LASTPROP $XRERR UNIQUE?
J 0
(-1105 -640);
DISPLAY 0.638298 (-1105 -640);
PAINT MONO (-1105 -640);
DISPLAY INVISIBLE (-1105 -640);
WIRE 16 -1 (-975 -650)(-975 -575);
WIRE 16 -1 (750 -650)(750 -475);
WIRE 16 -1 (750 -475)(1000 -475);
WIRE 3 2175 (-200 -525)(175 -525);
WIRE 3 2175 (-200 -250)(-200 -525);
WIRE 3 2175 (175 -250)(175 -525);
WIRE 3 2175 (-200 -250)(175 -250);
WIRE 3 2175 (-450 2125)(-75 2125);
WIRE 3 2175 (-450 2125)(-450 1800);
WIRE 3 2175 (-75 2125)(-75 1800);
WIRE 3 2175 (-450 1800)(-75 1800);
WIRE 16 -1 (-1125 1725)(600 1725);
FORCEPROP 2 LAST SIG_NAME VR_PVDDQ_GHJ_PH1_PHASE
J 0
(-1040 1735);
DISPLAY 0.617021 (-1040 1735);
PAINT ORANGE (-1040 1735);
FORCEPROP 2 LASTPROP $XRERR UNIQUE?
J 0
(-1280 1735);
DISPLAY 0.638298 (-1280 1735);
PAINT MONO (-1280 1735);
DISPLAY INVISIBLE (-1280 1735);
WIRE 16 -1 (-1125 1725)(-1125 1800);
WIRE 16 -1 (600 1725)(600 1900);
WIRE 16 -1 (600 1900)(975 1900);
WIRE 16 -1 (-175 2000)(600 2000);
FORCEPROP 2 LAST SIG_NAME VR_PVDDQ_GHJ_PH1_BOOT_R
J 0
(-65 2010);
DISPLAY 0.617021 (-65 2010);
PAINT ORANGE (-65 2010);
FORCEPROP 2 LASTPROP $XRERR UNIQUE?
J 0
(-305 2010);
DISPLAY 0.638298 (-305 2010);
PAINT MONO (-305 2010);
DISPLAY INVISIBLE (-305 2010);
WIRE 16 -1 (600 2000)(600 1950);
WIRE 16 -1 (600 1950)(975 1950);
WIRE 16 -1 (2000 100)(2700 100);
FORCEPROP 2 LAST SIG_NAME A_TSENSE_PVDDQ_GHJ
J 0
(2037 110);
DISPLAY 0.617021 (2037 110);
PAINT ORANGE (2037 110);
WIRE 16 -1 (2000 100)(2000 -75);
WIRE 16 -1 (2700 100)(3425 100);
WIRE 16 -1 (2700 25)(2700 100);
WIRE 16 -1 (2000 175)(3050 175);
FORCEPROP 2 LAST SIG_NAME NC_PVDDQ_GHJ_PH2_P31
J 0
(2112 185);
DISPLAY 0.617021 (2112 185);
PAINT ORANGE (2112 185);
FORCEPROP 2 LASTPROP $XRERR UNIQUE?
J 0
(3080 175);
DISPLAY 0.638298 (3080 175);
PAINT MONO (3080 175);
DISPLAY INVISIBLE (3080 175);
WIRE 3 2175 (2375 1250)(2850 1250);
WIRE 3 2175 (2375 1925)(2375 1250);
WIRE 3 2175 (2850 1925)(2850 1250);
WIRE 3 2175 (2375 1925)(2850 1925);
WIRE 16 -1 (1975 1950)(2700 1950);
FORCEPROP 2 LAST SIG_NAME VR_PVDDQ_GHJ_PH1_SW
J 0
(2110 1960);
DISPLAY 0.617021 (2110 1960);
PAINT ORANGE (2110 1960);
FORCEPROP 2 LASTPROP $XRERR UNIQUE?
J 0
(1870 1960);
DISPLAY 0.638298 (1870 1960);
PAINT MONO (1870 1960);
DISPLAY INVISIBLE (1870 1960);
WIRE 16 -1 (2700 1950)(3000 1950);
WIRE 16 -1 (2700 1875)(2700 1950);
WIRE 3 2175 (550 -375)(1100 -375);
WIRE 3 2175 (550 -375)(550 -925);
WIRE 3 2175 (1100 -375)(1100 -925);
WIRE 3 2175 (550 -925)(1100 -925);
WIRE 16 -1 (25 -125)(1000 -125);
FORCEPROP 0 LAST SIG_NAME TP_PVDDQ_GHJ_PH2_GL_0
J 0
(52 -110);
DISPLAY 0.617021 (52 -110);
PAINT ORANGE (52 -110);
FORCEPROP 2 LASTPROP $XRERR UNIQUE?
J 0
(-215 -125);
DISPLAY 0.638298 (-215 -125);
PAINT MONO (-215 -125);
DISPLAY INVISIBLE (-215 -125);
WIRE 16 -1 (-375 2000)(-1125 2000);
FORCEPROP 2 LAST SIG_NAME VR_PVDDQ_GHJ_PH1_BOOT
J 0
(-1090 2010);
DISPLAY 0.617021 (-1090 2010);
PAINT ORANGE (-1090 2010);
FORCEPROP 2 LASTPROP $XRERR UNIQUE?
J 0
(-1330 2010);
DISPLAY 0.638298 (-1330 2010);
PAINT MONO (-1330 2010);
DISPLAY INVISIBLE (-1330 2010);
WIRE 16 2175 (-1475 2075)(-550 2075);
WIRE 16 2175 (-1475 2075)(-1475 1675);
WIRE 16 2175 (-550 2075)(-550 1675);
WIRE 16 2175 (-1475 1675)(-550 1675);
WIRE 16 -1 (-1775 -225)(1000 -225);
FORCEPROP 2 LAST SIG_NAME VR_PVDDQ_GHJ_PWM2
J 0
(-1788 -215);
DISPLAY 0.617021 (-1788 -215);
PAINT ORANGE (-1788 -215);
WIRE 16 2175 (-1300 -275)(-350 -275);
WIRE 16 2175 (-1300 -275)(-1300 -675);
WIRE 16 2175 (-350 -275)(-350 -675);
WIRE 16 2175 (-1300 -675)(-350 -675);
WIRE 16 -1 (-975 -325)(-50 -325);
FORCEPROP 2 LAST SIG_NAME VR_PVDDQ_GHJ_PH2_BOOT
J 0
(-915 -315);
DISPLAY 0.617021 (-915 -315);
PAINT ORANGE (-915 -315);
FORCEPROP 2 LASTPROP $XRERR UNIQUE?
J 0
(-1155 -315);
DISPLAY 0.638298 (-1155 -315);
PAINT MONO (-1155 -315);
DISPLAY INVISIBLE (-1155 -315);
WIRE 16 -1 (-975 -325)(-975 -375);
WIRE 16 -1 (750 -325)(750 -425);
WIRE 16 -1 (750 -325)(150 -325);
FORCEPROP 2 LAST SIG_NAME VR_PVDDQ_GHJ_PH2_BOOT_R
J 0
(210 -315);
DISPLAY 0.617021 (210 -315);
PAINT ORANGE (210 -315);
FORCEPROP 2 LASTPROP $XRERR UNIQUE?
J 0
(-30 -315);
DISPLAY 0.638298 (-30 -315);
PAINT MONO (-30 -315);
DISPLAY INVISIBLE (-30 -315);
WIRE 16 -1 (750 -425)(1000 -425);
WIRE 16 -1 (-1375 2800)(975 2800);
FORCEPROP 2 LAST SIG_NAME VR_PVDDQ_GHJ_PH1_VCIN
J 0
(-1315 2835);
DISPLAY 0.617021 (-1315 2835);
PAINT ORANGE (-1315 2835);
FORCEPROP 2 LASTPROP $XRERR UNIQUE?
J 0
(-1555 2835);
DISPLAY 0.638298 (-1555 2835);
PAINT MONO (-1555 2835);
DISPLAY INVISIBLE (-1555 2835);
WIRE 16 -1 (-1375 2800)(-1375 3050);
WIRE 16 -1 (-1375 2650)(-1375 2800);
WIRE 16 -1 (-1375 3050)(-1225 3050);
WIRE 16 2175 (-875 2675)(-125 2675);
WIRE 16 2175 (-875 2675)(-875 2275);
WIRE 16 2175 (-125 2675)(-125 2275);
WIRE 16 2175 (-875 2275)(-125 2275);
WIRE 16 -1 (1975 2475)(2600 2475);
FORCEPROP 2 LAST SIG_NAME A_TSENSE_PVDDQ_GHJ
J 0
(2212 2485);
DISPLAY 0.617021 (2212 2485);
PAINT ORANGE (2212 2485);
WIRE 16 -1 (1975 2475)(1975 2300);
WIRE 16 -1 (2600 2475)(3050 2475);
WIRE 16 -1 (2600 2325)(2600 2475);
WIRE 16 -1 (1975 2550)(2975 2550);
FORCEPROP 2 LAST SIG_NAME NC_PVDDQ_GHJ_PH1_P31
J 0
(2112 2560);
DISPLAY 0.617021 (2112 2560);
PAINT ORANGE (2112 2560);
FORCEPROP 2 LASTPROP $XRERR UNIQUE?
J 0
(3005 2550);
DISPLAY 0.638298 (3005 2550);
PAINT MONO (3005 2550);
DISPLAY INVISIBLE (3005 2550);
WIRE 16 -1 (975 2050)(700 2050);
WIRE 16 -1 (700 2050)(700 3150);
WIRE 16 -1 (700 1825)(700 2050);
WIRE 16 -1 (700 3150)(3350 3150);
FORCEPROP 2 LAST SIG_NAME VR_PVDDQ_GHJ_AIREF1
J 0
(2660 3164);
DISPLAY 0.617021 (2660 3164);
PAINT ORANGE (2660 3164);
WIRE 16 -1 (2700 1725)(2700 1625);
WIRE 16 -1 (-2000 2150)(975 2150);
WIRE 16 -1 (0 2300)(975 2300);
FORCEPROP 0 LAST SIG_NAME TP_PVDDQ_GHJ_PH1_GL_1
J 0
(27 2315);
DISPLAY 0.617021 (27 2315);
PAINT ORANGE (27 2315);
FORCEPROP 2 LASTPROP $XRERR UNIQUE?
J 0
(-240 2300);
DISPLAY 0.638298 (-240 2300);
PAINT MONO (-240 2300);
DISPLAY INVISIBLE (-240 2300);
WIRE 16 -1 (25 -75)(1000 -75);
FORCEPROP 0 LAST SIG_NAME TP_PVDDQ_GHJ_PH2_GL_1
J 0
(52 -60);
DISPLAY 0.617021 (52 -60);
PAINT ORANGE (52 -60);
FORCEPROP 2 LASTPROP $XRERR UNIQUE?
J 0
(-215 -75);
DISPLAY 0.638298 (-215 -75);
PAINT MONO (-215 -75);
DISPLAY INVISIBLE (-215 -75);
WIRE 16 -1 (1975 2800)(3275 2800);
FORCEPROP 2 LAST SIG_NAME ISENSE_PVDDQ_GHJ_PH1_IMON
J 0
(2362 2810);
DISPLAY 0.617021 (2362 2810);
PAINT ORANGE (2362 2810);
WIRE 16 -1 (1975 2600)(4275 2600);
FORCEPROP 0 LAST VOLTAGE 3.6
J 0
(2050 2675);
DISPLAY 1.021277 (2050 2675);
PAINT SKYBLUE (2050 2675);
DISPLAY INVISIBLE (2050 2675);
FORCEPROP 2 LAST SIG_NAME VR_PVDDQ_GHJ_PH1_OCSET
J 0
(2107 2616);
DISPLAY 0.617021 (2107 2616);
PAINT ORANGE (2107 2616);
FORCEPROP 2 LASTPROP $XRERR UNIQUE?
J 0
(1867 2616);
DISPLAY 0.638298 (1867 2616);
PAINT MONO (1867 2616);
DISPLAY INVISIBLE (1867 2616);
WIRE 16 -1 (4275 2500)(4275 2600);
WIRE 16 -1 (0 2250)(975 2250);
FORCEPROP 0 LAST SIG_NAME TP_PVDDQ_GHJ_PH1_GL_0
J 0
(27 2265);
DISPLAY 0.617021 (27 2265);
PAINT ORANGE (27 2265);
FORCEPROP 2 LASTPROP $XRERR UNIQUE?
J 0
(-240 2250);
DISPLAY 0.638298 (-240 2250);
PAINT MONO (-240 2250);
DISPLAY INVISIBLE (-240 2250);
WIRE 16 -1 (2000 425)(3600 425);
FORCEPROP 2 LAST SIG_NAME ISENSE_PVDDQ_GHJ_PH2_IMON
J 0
(2637 435);
DISPLAY 0.617021 (2637 435);
PAINT ORANGE (2637 435);
WIRE 16 -1 (2000 225)(4300 225);
FORCEPROP 0 LAST VOLTAGE 3.6
J 0
(2075 300);
DISPLAY 1.021277 (2075 300);
PAINT SKYBLUE (2075 300);
DISPLAY INVISIBLE (2075 300);
FORCEPROP 2 LAST SIG_NAME VR_PVDDQ_GHJ_PH2_OCSET
J 0
(2132 241);
DISPLAY 0.617021 (2132 241);
PAINT ORANGE (2132 241);
FORCEPROP 2 LASTPROP $XRERR UNIQUE?
J 0
(1892 241);
DISPLAY 0.638298 (1892 241);
PAINT MONO (1892 241);
DISPLAY INVISIBLE (1892 241);
WIRE 16 -1 (4300 125)(4300 225);
WIRE 16 -1 (2800 -750)(2800 -650);
DOT 1 (3575 1950);
DOT 1 (2700 100);
DOT 1 (800 -325);
DOT 1 (2325 1800);
DOT 1 (2600 2475);
DOT 1 (-525 2200);
DOT 1 (-2725 -150);
DOT 1 (-2475 -150);
DOT 1 (-2225 -150);
DOT 1 (-1975 -150);
DOT 1 (-1725 -150);
DOT 1 (-1425 -150);
DOT 1 (-575 -150);
DOT 1 (-2725 325);
DOT 1 (-2475 325);
DOT 1 (-2225 325);
DOT 1 (-2700 2200);
DOT 1 (-2700 2700);
DOT 1 (-2450 2200);
DOT 1 (-2175 2200);
DOT 1 (-2450 2700);
DOT 1 (-2175 2700);
DOT 1 (-1975 325);
DOT 1 (-1725 325);
DOT 1 (-1425 425);
DOT 1 (-575 675);
DOT 1 (-475 675);
DOT 1 (-1925 2200);
DOT 1 (-1675 2200);
DOT 1 (-1925 2700);
DOT 1 (-1675 2700);
DOT 1 (-1375 2200);
DOT 1 (-1375 2800);
DOT 1 (-525 3050);
DOT 1 (-400 3050);
DOT 1 (0 3050);
DOT 1 (2325 -675);
DOT 1 (2325 -625);
DOT 1 (2325 -575);
DOT 1 (3525 -425);
DOT 1 (4000 -425);
DOT 1 (200 675);
DOT 1 (725 325);
DOT 1 (925 225);
DOT 1 (725 2700);
DOT 1 (825 2600);
DOT 1 (2325 1750);
DOT 1 (2325 1700);
DOT 1 (4000 1950);
DOT 1 (700 2050);
DOT 1 (2700 1950);
DOT 1 (2800 -425);
FORCENOTE
ROOM = VDDQ_GHJ_PWR_VR
(-3005 -1400) 0;
DISPLAY LEFT (-3005 -1400);
DISPLAY 2.893617 (-3005 -1400);
PAINT PURPLE (-3005 -1400);
FORCENOTE
TP FAB1 CO-LAY WITH TI PARTS 11/16
(-375 -800) 0;
DISPLAY LEFT (-375 -800);
DISPLAY 0.851064 (-375 -800);
PAINT RED (-375 -800);
FORCENOTE
PLACE ON TOP
(-880 2200) 0;
DISPLAY LEFT (-880 2200);
DISPLAY 1.553191 (-880 2200);
PAINT PURPLE (-880 2200);
FORCENOTE
SPOF
(-1055 -775) 0;
DISPLAY LEFT (-1055 -775);
DISPLAY 1.808511 (-1055 -775);
PAINT PURPLE (-1055 -775);
FORCENOTE
PLACE ON TOP
(-930 -175) 0;
DISPLAY LEFT (-930 -175);
DISPLAY 1.553191 (-930 -175);
PAINT PURPLE (-930 -175);
FORCENOTE
SPOF
(-1080 1550) 0;
DISPLAY LEFT (-1080 1550);
DISPLAY 1.936170 (-1080 1550);
PAINT PURPLE (-1080 1550);
FORCENOTE
TP FAB1 CO-LAY WITH TI PARTS 11/16
(2900 2250) 0;
DISPLAY LEFT (2900 2250);
DISPLAY 0.851064 (2900 2250);
PAINT RED (2900 2250);
FORCENOTE
TP FAB1 CO-LAY WITH TI PARTS 11/16
(-475 1525) 0;
DISPLAY LEFT (-475 1525);
DISPLAY 0.851064 (-475 1525);
PAINT RED (-475 1525);
FORCENOTE
TP FAB1 CO-LAY WITH TI PARTS 11/16
(2900 1125) 0;
DISPLAY LEFT (2900 1125);
DISPLAY 0.851064 (2900 1125);
PAINT RED (2900 1125);
FORCENOTE
TP FAB1 3.01 OHM NEED CHANGE TO 2.2 OHM BUT WAIT FOR SYMBOL
(2900 1075) 0;
DISPLAY LEFT (2900 1075);
DISPLAY 0.851064 (2900 1075);
PAINT RED (2900 1075);
FORCENOTE
TP FAB1 CO-LAY WITH TI PARTS 11/16
(3000 -150) 0;
DISPLAY LEFT (3000 -150);
DISPLAY 0.851064 (3000 -150);
PAINT RED (3000 -150);
FORCENOTE
TP FAB1 3.01 OHM NEED CHANGE TO 2.2 OHM BUT WAIT FOR SYMBOL
(3000 -950) 0;
DISPLAY LEFT (3000 -950);
DISPLAY 0.851064 (3000 -950);
PAINT RED (3000 -950);
FORCENOTE
TP FAB1 CO-LAY WITH TI PARTS 11/16
(3000 -875) 0;
DISPLAY LEFT (3000 -875);
DISPLAY 0.851064 (3000 -875);
PAINT RED (3000 -875);
QUIT
